G04*
G04 #@! TF.GenerationSoftware,Altium Limited,Altium Designer,23.7.1 (13)*
G04*
G04 Layer_Color=8421504*
%FSLAX25Y25*%
%MOIN*%
G70*
G04*
G04 #@! TF.SameCoordinates,AF00DCEB-AC48-4C7C-91EA-99F42E284231*
G04*
G04*
G04 #@! TF.FilePolarity,Positive*
G04*
G01*
G75*
G04:AMPARAMS|DCode=31|XSize=36.97mil|YSize=36.97mil|CornerRadius=2.03mil|HoleSize=0mil|Usage=FLASHONLY|Rotation=90.000|XOffset=0mil|YOffset=0mil|HoleType=Round|Shape=RoundedRectangle|*
%AMROUNDEDRECTD31*
21,1,0.03697,0.03290,0,0,90.0*
21,1,0.03290,0.03697,0,0,90.0*
1,1,0.00407,0.01645,0.01645*
1,1,0.00407,0.01645,-0.01645*
1,1,0.00407,-0.01645,-0.01645*
1,1,0.00407,-0.01645,0.01645*
%
%ADD31ROUNDEDRECTD31*%
%ADD32C,0.02500*%
%ADD33R,0.01968X0.00787*%
%ADD34R,0.00787X0.01968*%
%ADD35R,0.00787X0.01968*%
%ADD36R,0.01968X0.00787*%
%ADD37R,0.07178X0.03634*%
%ADD38R,0.12795X0.12795*%
%ADD39R,0.01024X0.03543*%
%ADD40R,0.03543X0.01024*%
%ADD41R,0.03740X0.03740*%
%ADD42R,0.01772X0.01772*%
%ADD43R,0.04331X0.04134*%
%ADD44R,0.03543X0.02953*%
%ADD45R,0.03543X0.03150*%
%ADD46R,0.04134X0.04331*%
%ADD47R,0.05709X0.04528*%
%ADD48R,0.05709X0.07480*%
%ADD49R,0.05512X0.03937*%
%ADD50R,0.03543X0.03937*%
%ADD51C,0.02918*%
%ADD52R,0.01457X0.00945*%
%ADD53R,0.01575X0.04252*%
%ADD54R,0.07835X0.09173*%
G04:AMPARAMS|DCode=55|XSize=11.81mil|YSize=29.53mil|CornerRadius=1.95mil|HoleSize=0mil|Usage=FLASHONLY|Rotation=180.000|XOffset=0mil|YOffset=0mil|HoleType=Round|Shape=RoundedRectangle|*
%AMROUNDEDRECTD55*
21,1,0.01181,0.02563,0,0,180.0*
21,1,0.00791,0.02953,0,0,180.0*
1,1,0.00390,-0.00396,0.01282*
1,1,0.00390,0.00396,0.01282*
1,1,0.00390,0.00396,-0.01282*
1,1,0.00390,-0.00396,-0.01282*
%
%ADD55ROUNDEDRECTD55*%
G04:AMPARAMS|DCode=56|XSize=11.81mil|YSize=29.53mil|CornerRadius=1.95mil|HoleSize=0mil|Usage=FLASHONLY|Rotation=90.000|XOffset=0mil|YOffset=0mil|HoleType=Round|Shape=RoundedRectangle|*
%AMROUNDEDRECTD56*
21,1,0.01181,0.02563,0,0,90.0*
21,1,0.00791,0.02953,0,0,90.0*
1,1,0.00390,0.01282,0.00396*
1,1,0.00390,0.01282,-0.00396*
1,1,0.00390,-0.01282,-0.00396*
1,1,0.00390,-0.01282,0.00396*
%
%ADD56ROUNDEDRECTD56*%
%ADD57R,0.05315X0.01575*%
%ADD58R,0.07480X0.07087*%
%ADD59R,0.08287X0.04409*%
%ADD60R,0.01968X0.01772*%
%ADD61R,0.03150X0.03150*%
%ADD62R,0.05000X0.02992*%
%ADD63R,0.09600X0.04400*%
%ADD64R,0.02165X0.02165*%
%ADD65R,0.07100X0.07100*%
%ADD66R,0.01000X0.03200*%
%ADD67R,0.03200X0.01000*%
%ADD68R,0.01772X0.01968*%
%ADD69R,0.02165X0.02165*%
%ADD70R,0.06102X0.01181*%
%ADD71R,0.10827X0.04724*%
%ADD72R,0.01181X0.06102*%
%ADD73R,0.04724X0.10827*%
%ADD74R,0.09800X0.03700*%
%ADD75R,0.23300X0.21700*%
%ADD76R,0.00984X0.01870*%
%ADD77R,0.01870X0.01378*%
%ADD78R,0.05100X0.03500*%
%ADD79R,0.08300X0.03500*%
%ADD80R,0.08300X0.07400*%
%ADD81R,0.02600X0.07400*%
%ADD82R,0.01400X0.07400*%
%ADD83R,0.02000X0.01300*%
%ADD84R,0.01300X0.02000*%
%ADD85R,0.09173X0.07835*%
%ADD86R,0.02816X0.02648*%
%ADD87R,0.02016X0.02288*%
%ADD88R,0.02911X0.02648*%
%ADD89R,0.02756X0.02756*%
G04:AMPARAMS|DCode=90|XSize=40.88mil|YSize=20.95mil|CornerRadius=10.48mil|HoleSize=0mil|Usage=FLASHONLY|Rotation=270.000|XOffset=0mil|YOffset=0mil|HoleType=Round|Shape=RoundedRectangle|*
%AMROUNDEDRECTD90*
21,1,0.04088,0.00000,0,0,270.0*
21,1,0.01993,0.02095,0,0,270.0*
1,1,0.02095,0.00000,-0.00996*
1,1,0.02095,0.00000,0.00996*
1,1,0.02095,0.00000,0.00996*
1,1,0.02095,0.00000,-0.00996*
%
%ADD90ROUNDEDRECTD90*%
%ADD91R,0.02095X0.04088*%
G04:AMPARAMS|DCode=92|XSize=61.02mil|YSize=23.62mil|CornerRadius=2.01mil|HoleSize=0mil|Usage=FLASHONLY|Rotation=90.000|XOffset=0mil|YOffset=0mil|HoleType=Round|Shape=RoundedRectangle|*
%AMROUNDEDRECTD92*
21,1,0.06102,0.01961,0,0,90.0*
21,1,0.05701,0.02362,0,0,90.0*
1,1,0.00402,0.00980,0.02850*
1,1,0.00402,0.00980,-0.02850*
1,1,0.00402,-0.00980,-0.02850*
1,1,0.00402,-0.00980,0.02850*
%
%ADD92ROUNDEDRECTD92*%
%ADD93R,0.05906X0.07284*%
G04:AMPARAMS|DCode=94|XSize=61.02mil|YSize=23.62mil|CornerRadius=2.01mil|HoleSize=0mil|Usage=FLASHONLY|Rotation=0.000|XOffset=0mil|YOffset=0mil|HoleType=Round|Shape=RoundedRectangle|*
%AMROUNDEDRECTD94*
21,1,0.06102,0.01961,0,0,0.0*
21,1,0.05701,0.02362,0,0,0.0*
1,1,0.00402,0.02850,-0.00980*
1,1,0.00402,-0.02850,-0.00980*
1,1,0.00402,-0.02850,0.00980*
1,1,0.00402,0.02850,0.00980*
%
%ADD94ROUNDEDRECTD94*%
%ADD95R,0.04546X0.06717*%
%ADD96R,0.03500X0.05100*%
%ADD97R,0.03500X0.08300*%
%ADD98R,0.07400X0.08300*%
%ADD99R,0.07400X0.02600*%
%ADD100R,0.07400X0.01400*%
%ADD101R,0.06717X0.04546*%
%ADD102R,0.04331X0.05315*%
%ADD103R,0.07874X0.11811*%
%ADD104R,0.11811X0.07874*%
%ADD105R,0.02631X0.02648*%
%ADD106R,0.02559X0.02362*%
%ADD107R,0.00984X0.06102*%
%ADD108R,0.05315X0.06693*%
%ADD109O,0.02362X0.08661*%
%ADD110O,0.02362X0.07480*%
%ADD111R,0.07480X0.04331*%
%ADD112R,0.02835X0.02835*%
%ADD113R,0.02648X0.02911*%
%ADD114R,0.04409X0.08287*%
%ADD115R,0.03543X0.01968*%
%ADD116R,0.03740X0.05709*%
%ADD117R,0.04134X0.03937*%
%ADD118R,0.08661X0.04134*%
%ADD119R,0.02362X0.02559*%
%ADD120R,0.02288X0.02016*%
%ADD121R,0.03937X0.05512*%
%ADD122R,0.05512X0.05512*%
%ADD123R,0.14488X0.05000*%
%ADD124R,0.02648X0.02816*%
%ADD125R,0.01378X0.01968*%
%ADD126R,0.03543X0.02362*%
%ADD127R,0.02165X0.02362*%
%ADD128R,0.01870X0.01968*%
G04:AMPARAMS|DCode=129|XSize=33.06mil|YSize=8.76mil|CornerRadius=4.38mil|HoleSize=0mil|Usage=FLASHONLY|Rotation=90.000|XOffset=0mil|YOffset=0mil|HoleType=Round|Shape=RoundedRectangle|*
%AMROUNDEDRECTD129*
21,1,0.03306,0.00000,0,0,90.0*
21,1,0.02430,0.00876,0,0,90.0*
1,1,0.00876,0.00000,0.01215*
1,1,0.00876,0.00000,-0.01215*
1,1,0.00876,0.00000,-0.01215*
1,1,0.00876,0.00000,0.01215*
%
%ADD129ROUNDEDRECTD129*%
%ADD130R,0.00876X0.03306*%
%ADD131R,0.05142X0.04166*%
%ADD132R,0.01968X0.01968*%
%ADD133R,0.09449X0.12992*%
%ADD134R,0.06693X0.05315*%
%ADD135R,0.06102X0.00984*%
%ADD136R,0.07087X0.00984*%
%ADD137R,0.07480X0.05709*%
%ADD138R,0.03347X0.01181*%
%ADD139R,0.03543X0.02756*%
%ADD140R,0.02756X0.03543*%
%ADD141R,0.02800X0.16500*%
%ADD142R,0.02800X0.12600*%
%ADD143R,0.03937X0.02835*%
%ADD144R,0.07480X0.06201*%
G36*
X510723Y14449D02*
X511046D01*
Y14417D01*
X511207D01*
Y14385D01*
X511336D01*
Y14353D01*
X511401D01*
Y14320D01*
X511497D01*
Y14288D01*
X511562D01*
Y14256D01*
X511659D01*
Y14224D01*
X511691D01*
Y14191D01*
X511756D01*
Y14159D01*
X511820D01*
Y14127D01*
X511852D01*
Y14095D01*
X511917D01*
Y14062D01*
X511949D01*
Y14030D01*
X512014D01*
Y13998D01*
X512046D01*
Y13965D01*
X512078D01*
Y13933D01*
X512110D01*
Y13901D01*
X512143D01*
Y13869D01*
X512175D01*
Y13836D01*
X512207D01*
Y13804D01*
X512239D01*
Y13772D01*
X512272D01*
Y13740D01*
X512304D01*
Y13707D01*
X512336D01*
Y13675D01*
X512368D01*
Y13643D01*
Y13611D01*
X512401D01*
Y13578D01*
X512433D01*
Y13546D01*
Y13514D01*
X512465D01*
Y13482D01*
X512498D01*
Y13449D01*
Y13417D01*
X512530D01*
Y13385D01*
Y13352D01*
X512562D01*
Y13320D01*
X512594D01*
Y13288D01*
Y13256D01*
X512627D01*
Y13223D01*
Y13191D01*
Y13159D01*
X512659D01*
Y13127D01*
Y13094D01*
X512691D01*
Y13062D01*
Y13030D01*
Y12998D01*
X512723D01*
Y12965D01*
Y12933D01*
Y12901D01*
Y12869D01*
X512756D01*
Y12836D01*
Y12804D01*
Y12772D01*
Y12740D01*
X512788D01*
Y12707D01*
Y12675D01*
Y12643D01*
Y12610D01*
Y12578D01*
Y12546D01*
Y12514D01*
Y12481D01*
Y12449D01*
Y12417D01*
X512820D01*
Y12385D01*
Y12352D01*
Y12320D01*
Y12288D01*
X512788D01*
Y12256D01*
Y12223D01*
Y12191D01*
Y12159D01*
Y12127D01*
Y12094D01*
Y12062D01*
Y12030D01*
Y11998D01*
X512756D01*
Y11965D01*
Y11933D01*
Y11901D01*
Y11868D01*
Y11836D01*
X512723D01*
Y11804D01*
Y11772D01*
Y11739D01*
X512691D01*
Y11707D01*
Y11675D01*
Y11643D01*
X512659D01*
Y11610D01*
Y11578D01*
Y11546D01*
X512627D01*
Y11514D01*
Y11481D01*
X512594D01*
Y11449D01*
Y11417D01*
X512562D01*
Y11384D01*
Y11352D01*
X512530D01*
Y11320D01*
Y11288D01*
X512498D01*
Y11255D01*
Y11223D01*
X512465D01*
Y11191D01*
X512433D01*
Y11159D01*
Y11126D01*
X512401D01*
Y11094D01*
X512368D01*
Y11062D01*
X512336D01*
Y11030D01*
Y10997D01*
X512304D01*
Y10965D01*
X512272D01*
Y10933D01*
X512239D01*
Y10901D01*
X512207D01*
Y10868D01*
X512175D01*
Y10836D01*
X512143D01*
Y10804D01*
X512110D01*
Y10772D01*
X512078D01*
Y10739D01*
X512014D01*
Y10707D01*
X511981D01*
Y10675D01*
X511949D01*
Y10643D01*
X511917D01*
Y10610D01*
X511852D01*
Y10578D01*
X511820D01*
Y10546D01*
X511756D01*
Y10514D01*
X511691D01*
Y10481D01*
X511626D01*
Y10449D01*
X511562D01*
Y10417D01*
X511497D01*
Y10384D01*
X511401D01*
Y10352D01*
X511304D01*
Y10320D01*
X511175D01*
Y10288D01*
X511014D01*
Y10255D01*
X507884D01*
Y10288D01*
X507723D01*
Y10320D01*
X507626D01*
Y10352D01*
X507529D01*
Y10384D01*
X507432D01*
Y10417D01*
X507368D01*
Y10449D01*
X507271D01*
Y10481D01*
X507239D01*
Y10514D01*
X507174D01*
Y10546D01*
X507110D01*
Y10578D01*
X507078D01*
Y10610D01*
X507013D01*
Y10643D01*
X506981D01*
Y10675D01*
X506916D01*
Y10707D01*
X506884D01*
Y10739D01*
X506852D01*
Y10772D01*
X506819D01*
Y10804D01*
X506787D01*
Y10836D01*
X506755D01*
Y10868D01*
X506723D01*
Y10901D01*
X506690D01*
Y10933D01*
X506658D01*
Y10965D01*
X506626D01*
Y10997D01*
X506594D01*
Y11030D01*
X506561D01*
Y11062D01*
Y11094D01*
X506529D01*
Y11126D01*
X506497D01*
Y11159D01*
X506464D01*
Y11191D01*
Y11223D01*
X506432D01*
Y11255D01*
Y11288D01*
X506400D01*
Y11320D01*
X506368D01*
Y11352D01*
Y11384D01*
X506335D01*
Y11417D01*
Y11449D01*
X506303D01*
Y11481D01*
Y11514D01*
X506271D01*
Y11546D01*
Y11578D01*
Y11610D01*
X506239D01*
Y11643D01*
Y11675D01*
Y11707D01*
X506207D01*
Y11739D01*
Y11772D01*
Y11804D01*
X506174D01*
Y11836D01*
Y11868D01*
Y11901D01*
Y11933D01*
Y11965D01*
X506142D01*
Y11998D01*
Y12030D01*
Y12062D01*
Y12094D01*
Y12127D01*
X506110D01*
Y12159D01*
Y12191D01*
Y12223D01*
Y12256D01*
Y12288D01*
Y12320D01*
Y12352D01*
Y12385D01*
Y12417D01*
Y12449D01*
Y12481D01*
Y12514D01*
Y12546D01*
X506142D01*
Y12578D01*
Y12610D01*
Y12643D01*
Y12675D01*
Y12707D01*
Y12740D01*
Y12772D01*
X506174D01*
Y12804D01*
Y12836D01*
Y12869D01*
Y12901D01*
X506207D01*
Y12933D01*
Y12965D01*
Y12998D01*
Y13030D01*
X506239D01*
Y13062D01*
Y13094D01*
X506271D01*
Y13127D01*
Y13159D01*
Y13191D01*
X506303D01*
Y13223D01*
Y13256D01*
X506335D01*
Y13288D01*
Y13320D01*
X506368D01*
Y13352D01*
Y13385D01*
X506400D01*
Y13417D01*
Y13449D01*
X506432D01*
Y13482D01*
X506464D01*
Y13514D01*
Y13546D01*
X506497D01*
Y13578D01*
X506529D01*
Y13611D01*
Y13643D01*
X506561D01*
Y13675D01*
X506594D01*
Y13707D01*
X506626D01*
Y13740D01*
X506658D01*
Y13772D01*
X506690D01*
Y13804D01*
X506723D01*
Y13836D01*
X506755D01*
Y13869D01*
X506787D01*
Y13901D01*
X506819D01*
Y13933D01*
X506852D01*
Y13965D01*
X506884D01*
Y13998D01*
X506916D01*
Y14030D01*
X506949D01*
Y14062D01*
X507013D01*
Y14095D01*
X507045D01*
Y14127D01*
X507110D01*
Y14159D01*
X507142D01*
Y14191D01*
X507207D01*
Y14224D01*
X507271D01*
Y14256D01*
X507336D01*
Y14288D01*
X507432D01*
Y14320D01*
X507497D01*
Y14353D01*
X507594D01*
Y14385D01*
X507723D01*
Y14417D01*
X507852D01*
Y14449D01*
X508207D01*
Y14482D01*
X510659D01*
Y14449D01*
X510691D01*
Y14482D01*
X510723D01*
Y14449D01*
D02*
G37*
G36*
X461846Y964D02*
X461976D01*
Y932D01*
X462072D01*
Y900D01*
X462137D01*
Y867D01*
X462201D01*
Y835D01*
X462234D01*
Y803D01*
X462298D01*
Y770D01*
X462330D01*
Y738D01*
X462395D01*
Y706D01*
X462427D01*
Y674D01*
X462460D01*
Y641D01*
X462492D01*
Y609D01*
X462524D01*
Y577D01*
X462556D01*
Y545D01*
Y512D01*
X462589D01*
Y480D01*
X462621D01*
Y448D01*
Y416D01*
X462653D01*
Y383D01*
X462685D01*
Y351D01*
Y319D01*
X462718D01*
Y286D01*
Y254D01*
Y222D01*
X462750D01*
Y190D01*
Y157D01*
Y125D01*
X462782D01*
Y93D01*
Y61D01*
Y28D01*
Y-4D01*
X462814D01*
Y-36D01*
Y-68D01*
Y-101D01*
Y-133D01*
Y-165D01*
Y-197D01*
Y-230D01*
Y-262D01*
Y-294D01*
Y-326D01*
Y-359D01*
Y-391D01*
Y-423D01*
X462782D01*
Y-455D01*
Y-488D01*
Y-520D01*
Y-552D01*
X462750D01*
Y-585D01*
Y-617D01*
Y-649D01*
X462718D01*
Y-681D01*
Y-714D01*
X462685D01*
Y-746D01*
Y-778D01*
X462653D01*
Y-810D01*
Y-843D01*
X462621D01*
Y-875D01*
X462589D01*
Y-907D01*
Y-939D01*
X462556D01*
Y-972D01*
X462524D01*
Y-1004D01*
X462492D01*
Y-1036D01*
X462460D01*
Y-1068D01*
X462427D01*
Y-1101D01*
X462395D01*
Y-1133D01*
X462363D01*
Y-1165D01*
X462330D01*
Y-1198D01*
X462266D01*
Y-1230D01*
X462234D01*
Y-1262D01*
X462169D01*
Y-1294D01*
X462105D01*
Y-1327D01*
X462008D01*
Y-1359D01*
X461911D01*
Y-1391D01*
X461718D01*
Y-1423D01*
X461492D01*
Y-1391D01*
X461298D01*
Y-1359D01*
X461201D01*
Y-1327D01*
X461137D01*
Y-1294D01*
X461040D01*
Y-1262D01*
X461008D01*
Y-1230D01*
X460943D01*
Y-1198D01*
X460911D01*
Y-1165D01*
X460846D01*
Y-1133D01*
X460814D01*
Y-1101D01*
X460782D01*
Y-1068D01*
X460750D01*
Y-1036D01*
X460717D01*
Y-1004D01*
X460685D01*
Y-972D01*
X460653D01*
Y-939D01*
X460620D01*
Y-907D01*
Y-875D01*
X460588D01*
Y-843D01*
Y-810D01*
X460556D01*
Y-778D01*
X460524D01*
Y-746D01*
Y-714D01*
X460492D01*
Y-681D01*
Y-649D01*
Y-617D01*
X460459D01*
Y-585D01*
Y-552D01*
Y-520D01*
X460427D01*
Y-488D01*
Y-455D01*
Y-423D01*
Y-391D01*
Y-359D01*
X460395D01*
Y-326D01*
Y-294D01*
Y-262D01*
Y-230D01*
Y-197D01*
Y-165D01*
Y-133D01*
Y-101D01*
Y-68D01*
Y-36D01*
X460427D01*
Y-4D01*
Y28D01*
Y61D01*
Y93D01*
Y125D01*
X460459D01*
Y157D01*
Y190D01*
Y222D01*
X460492D01*
Y254D01*
Y286D01*
X460524D01*
Y319D01*
Y351D01*
X460556D01*
Y383D01*
Y416D01*
X460588D01*
Y448D01*
Y480D01*
X460620D01*
Y512D01*
X460653D01*
Y545D01*
X460685D01*
Y577D01*
Y609D01*
X460717D01*
Y641D01*
X460750D01*
Y674D01*
X460782D01*
Y706D01*
X460846D01*
Y738D01*
X460879D01*
Y770D01*
X460911D01*
Y803D01*
X460975D01*
Y835D01*
X461008D01*
Y867D01*
X461072D01*
Y900D01*
X461169D01*
Y932D01*
X461234D01*
Y964D01*
X461363D01*
Y996D01*
X461846D01*
Y964D01*
D02*
G37*
G36*
X461814Y-3391D02*
X461943D01*
Y-3424D01*
X462040D01*
Y-3456D01*
X462105D01*
Y-3488D01*
X462169D01*
Y-3520D01*
X462234D01*
Y-3553D01*
X462298D01*
Y-3585D01*
X462330D01*
Y-3617D01*
X462363D01*
Y-3650D01*
X462427D01*
Y-3682D01*
X462460D01*
Y-3714D01*
X462492D01*
Y-3746D01*
X462524D01*
Y-3779D01*
Y-3811D01*
X462556D01*
Y-3843D01*
X462589D01*
Y-3875D01*
X462621D01*
Y-3907D01*
Y-3940D01*
X462653D01*
Y-3972D01*
Y-4004D01*
X462685D01*
Y-4037D01*
Y-4069D01*
X462718D01*
Y-4101D01*
Y-4133D01*
X462750D01*
Y-4166D01*
Y-4198D01*
Y-4230D01*
X462782D01*
Y-4262D01*
Y-4295D01*
Y-4327D01*
Y-4359D01*
X462814D01*
Y-4391D01*
Y-4424D01*
Y-4456D01*
Y-4488D01*
Y-4521D01*
Y-4553D01*
Y-4585D01*
Y-4617D01*
Y-4650D01*
Y-4682D01*
Y-4714D01*
Y-4746D01*
Y-4779D01*
X462782D01*
Y-4811D01*
Y-4843D01*
Y-4875D01*
Y-4908D01*
X462750D01*
Y-4940D01*
Y-4972D01*
Y-5004D01*
X462718D01*
Y-5037D01*
Y-5069D01*
X462685D01*
Y-5101D01*
Y-5133D01*
X462653D01*
Y-5166D01*
Y-5198D01*
X462621D01*
Y-5230D01*
Y-5263D01*
X462589D01*
Y-5295D01*
X462556D01*
Y-5327D01*
X462524D01*
Y-5359D01*
Y-5392D01*
X462492D01*
Y-5424D01*
X462460D01*
Y-5456D01*
X462395D01*
Y-5488D01*
X462363D01*
Y-5521D01*
X462330D01*
Y-5553D01*
X462298D01*
Y-5585D01*
X462234D01*
Y-5617D01*
X462169D01*
Y-5650D01*
X462105D01*
Y-5682D01*
X462040D01*
Y-5714D01*
X461943D01*
Y-5746D01*
X461782D01*
Y-5779D01*
X461427D01*
Y-5746D01*
X461266D01*
Y-5714D01*
X461169D01*
Y-5682D01*
X461104D01*
Y-5650D01*
X461040D01*
Y-5617D01*
X460975D01*
Y-5585D01*
X460943D01*
Y-5553D01*
X460879D01*
Y-5521D01*
X460846D01*
Y-5488D01*
X460814D01*
Y-5456D01*
X460782D01*
Y-5424D01*
X460750D01*
Y-5392D01*
X460717D01*
Y-5359D01*
X460685D01*
Y-5327D01*
X460653D01*
Y-5295D01*
X460620D01*
Y-5263D01*
Y-5230D01*
X460588D01*
Y-5198D01*
X460556D01*
Y-5166D01*
Y-5133D01*
X460524D01*
Y-5101D01*
Y-5069D01*
X460492D01*
Y-5037D01*
Y-5004D01*
Y-4972D01*
X460459D01*
Y-4940D01*
Y-4908D01*
Y-4875D01*
X460427D01*
Y-4843D01*
Y-4811D01*
Y-4779D01*
Y-4746D01*
X460395D01*
Y-4714D01*
Y-4682D01*
Y-4650D01*
Y-4617D01*
Y-4585D01*
Y-4553D01*
Y-4521D01*
Y-4488D01*
Y-4456D01*
Y-4424D01*
Y-4391D01*
X460427D01*
Y-4359D01*
Y-4327D01*
Y-4295D01*
Y-4262D01*
X460459D01*
Y-4230D01*
Y-4198D01*
Y-4166D01*
Y-4133D01*
X460492D01*
Y-4101D01*
Y-4069D01*
X460524D01*
Y-4037D01*
Y-4004D01*
X460556D01*
Y-3972D01*
Y-3940D01*
X460588D01*
Y-3907D01*
X460620D01*
Y-3875D01*
Y-3843D01*
X460653D01*
Y-3811D01*
X460685D01*
Y-3779D01*
X460717D01*
Y-3746D01*
X460750D01*
Y-3714D01*
X460782D01*
Y-3682D01*
X460814D01*
Y-3650D01*
X460846D01*
Y-3617D01*
X460879D01*
Y-3585D01*
X460943D01*
Y-3553D01*
X460975D01*
Y-3520D01*
X461040D01*
Y-3488D01*
X461104D01*
Y-3456D01*
X461169D01*
Y-3424D01*
X461266D01*
Y-3391D01*
X461427D01*
Y-3359D01*
X461814D01*
Y-3391D01*
D02*
G37*
G36*
X518143Y-2391D02*
X518337D01*
Y-2424D01*
X518466D01*
Y-2456D01*
X518563D01*
Y-2488D01*
X518659D01*
Y-2520D01*
X518724D01*
Y-2553D01*
X518821D01*
Y-2585D01*
X518885D01*
Y-2617D01*
X518918D01*
Y-2649D01*
X518982D01*
Y-2682D01*
X519047D01*
Y-2714D01*
X519079D01*
Y-2746D01*
X519143D01*
Y-2778D01*
X519176D01*
Y-2811D01*
X519208D01*
Y-2843D01*
X519240D01*
Y-2875D01*
X519305D01*
Y-2907D01*
X519337D01*
Y-2940D01*
X519369D01*
Y-2972D01*
X519402D01*
Y-3004D01*
X519434D01*
Y-3036D01*
X519466D01*
Y-3069D01*
X519498D01*
Y-3101D01*
X519531D01*
Y-3133D01*
Y-3165D01*
X519563D01*
Y-3198D01*
X519595D01*
Y-3230D01*
X519627D01*
Y-3262D01*
Y-3295D01*
X519660D01*
Y-3327D01*
X519692D01*
Y-3359D01*
Y-3391D01*
X519724D01*
Y-3424D01*
Y-3456D01*
X519756D01*
Y-3488D01*
X519789D01*
Y-3520D01*
Y-3553D01*
X519821D01*
Y-3585D01*
Y-3617D01*
Y-3650D01*
X519853D01*
Y-3682D01*
Y-3714D01*
X519885D01*
Y-3746D01*
Y-3779D01*
Y-3811D01*
X519918D01*
Y-3843D01*
Y-3875D01*
Y-3907D01*
X519950D01*
Y-3940D01*
Y-3972D01*
Y-4004D01*
Y-4037D01*
X519982D01*
Y-4069D01*
Y-4101D01*
Y-4133D01*
Y-4166D01*
Y-4198D01*
Y-4230D01*
X520014D01*
Y-4262D01*
Y-4295D01*
Y-4327D01*
Y-4359D01*
Y-4391D01*
Y-4424D01*
Y-4456D01*
Y-4488D01*
Y-4521D01*
Y-4553D01*
Y-4585D01*
Y-4617D01*
Y-4650D01*
Y-4682D01*
Y-4714D01*
X519982D01*
Y-4746D01*
Y-4779D01*
Y-4811D01*
Y-4843D01*
Y-4875D01*
Y-4908D01*
X519950D01*
Y-4940D01*
Y-4972D01*
Y-5004D01*
Y-5037D01*
X519918D01*
Y-5069D01*
Y-5101D01*
Y-5133D01*
X519885D01*
Y-5166D01*
Y-5198D01*
Y-5230D01*
X519853D01*
Y-5263D01*
Y-5295D01*
X519821D01*
Y-5327D01*
Y-5359D01*
X519789D01*
Y-5392D01*
Y-5424D01*
X519756D01*
Y-5456D01*
Y-5488D01*
X519724D01*
Y-5521D01*
Y-5553D01*
X519692D01*
Y-5585D01*
X519660D01*
Y-5617D01*
Y-5650D01*
X519627D01*
Y-5682D01*
X519595D01*
Y-5714D01*
Y-5746D01*
X519563D01*
Y-5779D01*
X519531D01*
Y-5811D01*
X519498D01*
Y-5843D01*
X519466D01*
Y-5875D01*
X519434D01*
Y-5908D01*
X519402D01*
Y-5940D01*
X519369D01*
Y-5972D01*
X519337D01*
Y-6005D01*
X519305D01*
Y-6037D01*
X519273D01*
Y-6069D01*
X519240D01*
Y-6101D01*
X519208D01*
Y-6134D01*
X519143D01*
Y-6166D01*
X519111D01*
Y-6198D01*
X519079D01*
Y-6230D01*
X519014D01*
Y-6263D01*
X518950D01*
Y-6295D01*
X518918D01*
Y-6327D01*
X518853D01*
Y-6359D01*
X518789D01*
Y-6392D01*
X518692D01*
Y-6424D01*
X518627D01*
Y-6456D01*
X518531D01*
Y-6488D01*
X518401D01*
Y-6521D01*
X518240D01*
Y-6553D01*
X518047D01*
Y-6585D01*
X518014D01*
Y-6553D01*
X517982D01*
Y-6585D01*
X517950D01*
Y-6553D01*
X517917D01*
Y-6585D01*
X517692D01*
Y-6553D01*
X517466D01*
Y-6521D01*
X517305D01*
Y-6488D01*
X517208D01*
Y-6456D01*
X517111D01*
Y-6424D01*
X517014D01*
Y-6392D01*
X516950D01*
Y-6359D01*
X516885D01*
Y-6327D01*
X516821D01*
Y-6295D01*
X516756D01*
Y-6263D01*
X516724D01*
Y-6230D01*
X516659D01*
Y-6198D01*
X516627D01*
Y-6166D01*
X516563D01*
Y-6134D01*
X516530D01*
Y-6101D01*
X516498D01*
Y-6069D01*
X516466D01*
Y-6037D01*
X516401D01*
Y-6005D01*
X516369D01*
Y-5972D01*
X516337D01*
Y-5940D01*
X516304D01*
Y-5908D01*
X516272D01*
Y-5875D01*
X516240D01*
Y-5843D01*
Y-5811D01*
X516208D01*
Y-5779D01*
X516175D01*
Y-5746D01*
X516143D01*
Y-5714D01*
X516111D01*
Y-5682D01*
Y-5650D01*
X516079D01*
Y-5617D01*
X516046D01*
Y-5585D01*
Y-5553D01*
X516014D01*
Y-5521D01*
Y-5488D01*
X515982D01*
Y-5456D01*
X515949D01*
Y-5424D01*
Y-5392D01*
X515917D01*
Y-5359D01*
Y-5327D01*
X515885D01*
Y-5295D01*
Y-5263D01*
Y-5230D01*
X515853D01*
Y-5198D01*
Y-5166D01*
X515821D01*
Y-5133D01*
Y-5101D01*
Y-5069D01*
X515788D01*
Y-5037D01*
Y-5004D01*
Y-4972D01*
Y-4940D01*
X515756D01*
Y-4908D01*
Y-4875D01*
Y-4843D01*
Y-4811D01*
Y-4779D01*
X515724D01*
Y-4746D01*
Y-4714D01*
Y-4682D01*
Y-4650D01*
Y-4617D01*
Y-4585D01*
Y-4553D01*
Y-4521D01*
Y-4488D01*
Y-4456D01*
Y-4424D01*
Y-4391D01*
Y-4359D01*
Y-4327D01*
Y-4295D01*
Y-4262D01*
Y-4230D01*
Y-4198D01*
Y-4166D01*
X515756D01*
Y-4133D01*
Y-4101D01*
Y-4069D01*
Y-4037D01*
Y-4004D01*
X515788D01*
Y-3972D01*
Y-3940D01*
Y-3907D01*
Y-3875D01*
X515821D01*
Y-3843D01*
Y-3811D01*
Y-3779D01*
X515853D01*
Y-3746D01*
Y-3714D01*
Y-3682D01*
X515885D01*
Y-3650D01*
Y-3617D01*
X515917D01*
Y-3585D01*
Y-3553D01*
X515949D01*
Y-3520D01*
Y-3488D01*
X515982D01*
Y-3456D01*
Y-3424D01*
X516014D01*
Y-3391D01*
Y-3359D01*
X516046D01*
Y-3327D01*
X516079D01*
Y-3295D01*
Y-3262D01*
X516111D01*
Y-3230D01*
X516143D01*
Y-3198D01*
X516175D01*
Y-3165D01*
Y-3133D01*
X516208D01*
Y-3101D01*
X516240D01*
Y-3069D01*
X516272D01*
Y-3036D01*
X516304D01*
Y-3004D01*
X516337D01*
Y-2972D01*
X516369D01*
Y-2940D01*
X516401D01*
Y-2907D01*
X516433D01*
Y-2875D01*
X516466D01*
Y-2843D01*
X516498D01*
Y-2811D01*
X516563D01*
Y-2778D01*
X516595D01*
Y-2746D01*
X516659D01*
Y-2714D01*
X516691D01*
Y-2682D01*
X516756D01*
Y-2649D01*
X516788D01*
Y-2617D01*
X516853D01*
Y-2585D01*
X516917D01*
Y-2553D01*
X516982D01*
Y-2520D01*
X517079D01*
Y-2488D01*
X517175D01*
Y-2456D01*
X517272D01*
Y-2424D01*
X517401D01*
Y-2391D01*
X517563D01*
Y-2359D01*
X518143D01*
Y-2391D01*
D02*
G37*
G36*
X501012Y14449D02*
X501367D01*
Y14417D01*
X501496D01*
Y14385D01*
X501625D01*
Y14353D01*
X501722D01*
Y14320D01*
X501819D01*
Y14288D01*
X501883D01*
Y14256D01*
X501948D01*
Y14224D01*
X502012D01*
Y14191D01*
X502077D01*
Y14159D01*
X502142D01*
Y14127D01*
X502174D01*
Y14095D01*
X502238D01*
Y14062D01*
X502271D01*
Y14030D01*
X502303D01*
Y13998D01*
X502367D01*
Y13965D01*
X502400D01*
Y13933D01*
X502432D01*
Y13901D01*
X502464D01*
Y13869D01*
X502496D01*
Y13836D01*
X502529D01*
Y13804D01*
X502561D01*
Y13772D01*
X502593D01*
Y13740D01*
X502625D01*
Y13707D01*
X502658D01*
Y13675D01*
X502690D01*
Y13643D01*
Y13611D01*
X502722D01*
Y13578D01*
X502754D01*
Y13546D01*
X502787D01*
Y13514D01*
Y13482D01*
X502819D01*
Y13449D01*
Y13417D01*
X502851D01*
Y13385D01*
X502883D01*
Y13352D01*
Y13320D01*
X502916D01*
Y13288D01*
Y13256D01*
X502948D01*
Y13223D01*
Y13191D01*
X502980D01*
Y13159D01*
Y13127D01*
Y13094D01*
X503013D01*
Y13062D01*
Y13030D01*
Y12998D01*
X503045D01*
Y12965D01*
Y12933D01*
Y12901D01*
X503077D01*
Y12869D01*
Y12836D01*
Y12804D01*
Y12772D01*
X503109D01*
Y12740D01*
Y12707D01*
Y12675D01*
Y12643D01*
Y12610D01*
Y12578D01*
X503142D01*
Y12546D01*
Y12514D01*
Y12481D01*
Y12449D01*
Y12417D01*
Y12385D01*
Y12352D01*
Y12320D01*
Y12288D01*
Y12256D01*
Y12223D01*
X503109D01*
Y12191D01*
X503142D01*
Y12159D01*
X503109D01*
Y12127D01*
Y12094D01*
Y12062D01*
Y12030D01*
Y11998D01*
Y11965D01*
Y11933D01*
X503077D01*
Y11901D01*
Y11868D01*
Y11836D01*
Y11804D01*
X503045D01*
Y11772D01*
Y11739D01*
Y11707D01*
X503013D01*
Y11675D01*
Y11643D01*
Y11610D01*
X502980D01*
Y11578D01*
Y11546D01*
Y11514D01*
X502948D01*
Y11481D01*
Y11449D01*
X502916D01*
Y11417D01*
Y11384D01*
X502883D01*
Y11352D01*
Y11320D01*
X502851D01*
Y11288D01*
X502819D01*
Y11255D01*
Y11223D01*
X502787D01*
Y11191D01*
X502754D01*
Y11159D01*
Y11126D01*
X502722D01*
Y11094D01*
X502690D01*
Y11062D01*
X502658D01*
Y11030D01*
Y10997D01*
X502625D01*
Y10965D01*
X502593D01*
Y10933D01*
X502561D01*
Y10901D01*
X502529D01*
Y10868D01*
X502496D01*
Y10836D01*
X502464D01*
Y10804D01*
X502432D01*
Y10772D01*
X502400D01*
Y10739D01*
X502335D01*
Y10707D01*
X502303D01*
Y10675D01*
X502271D01*
Y10643D01*
X502206D01*
Y10610D01*
X502174D01*
Y10578D01*
X502109D01*
Y10546D01*
X502077D01*
Y10514D01*
X502012D01*
Y10481D01*
X501948D01*
Y10449D01*
X501883D01*
Y10417D01*
X501787D01*
Y10384D01*
X501722D01*
Y10352D01*
X501593D01*
Y10320D01*
X501496D01*
Y10288D01*
X501303D01*
Y10255D01*
X496431D01*
Y10223D01*
X496173D01*
Y10191D01*
X496044D01*
Y10159D01*
X495915D01*
Y10126D01*
X495850D01*
Y10094D01*
X495754D01*
Y10062D01*
X495689D01*
Y10029D01*
X495625D01*
Y9997D01*
X495560D01*
Y9965D01*
X495496D01*
Y9933D01*
X495463D01*
Y9900D01*
X495399D01*
Y9868D01*
X495334D01*
Y9836D01*
X495302D01*
Y9804D01*
X495270D01*
Y9771D01*
X495237D01*
Y9739D01*
X495173D01*
Y9707D01*
X495141D01*
Y9675D01*
X495108D01*
Y9642D01*
X495076D01*
Y9610D01*
X495044D01*
Y9578D01*
X495012D01*
Y9546D01*
X494979D01*
Y9513D01*
X494947D01*
Y9481D01*
Y9449D01*
X494915D01*
Y9417D01*
X494883D01*
Y9384D01*
X494850D01*
Y9352D01*
Y9320D01*
X494818D01*
Y9287D01*
X494786D01*
Y9255D01*
Y9223D01*
X494754D01*
Y9191D01*
X494721D01*
Y9159D01*
Y9126D01*
X494689D01*
Y9094D01*
Y9062D01*
X494657D01*
Y9029D01*
Y8997D01*
X494625D01*
Y8965D01*
Y8933D01*
Y8900D01*
X494592D01*
Y8868D01*
Y8836D01*
X494560D01*
Y8804D01*
Y8771D01*
Y8739D01*
X494528D01*
Y8707D01*
Y8675D01*
Y8642D01*
Y8610D01*
X494495D01*
Y8578D01*
Y8546D01*
Y8513D01*
Y8481D01*
Y8449D01*
Y8416D01*
X494463D01*
Y8384D01*
Y8352D01*
Y8320D01*
Y8287D01*
Y8255D01*
Y8223D01*
Y8191D01*
Y8158D01*
Y8126D01*
Y8094D01*
Y8062D01*
Y8029D01*
Y7997D01*
Y7965D01*
Y7932D01*
Y7900D01*
X494495D01*
Y7868D01*
Y7836D01*
Y7803D01*
Y7771D01*
Y7739D01*
Y7707D01*
X494528D01*
Y7674D01*
Y7642D01*
Y7610D01*
Y7578D01*
X494560D01*
Y7545D01*
Y7513D01*
Y7481D01*
X494592D01*
Y7449D01*
Y7416D01*
Y7384D01*
X494625D01*
Y7352D01*
Y7320D01*
X494657D01*
Y7287D01*
Y7255D01*
X494689D01*
Y7223D01*
Y7191D01*
X494721D01*
Y7158D01*
Y7126D01*
X494754D01*
Y7094D01*
Y7062D01*
X494786D01*
Y7029D01*
X494818D01*
Y6997D01*
Y6965D01*
X494850D01*
Y6932D01*
X494883D01*
Y6900D01*
Y6868D01*
X494915D01*
Y6836D01*
X494947D01*
Y6803D01*
X494979D01*
Y6771D01*
X495012D01*
Y6739D01*
X495044D01*
Y6707D01*
X495076D01*
Y6674D01*
X495108D01*
Y6642D01*
X495141D01*
Y6610D01*
X495173D01*
Y6577D01*
X495205D01*
Y6545D01*
X495237D01*
Y6513D01*
X495270D01*
Y6481D01*
X495334D01*
Y6448D01*
X495366D01*
Y6416D01*
X495431D01*
Y6384D01*
X495463D01*
Y6352D01*
X495528D01*
Y6319D01*
X495592D01*
Y6287D01*
X495657D01*
Y6255D01*
X495721D01*
Y6223D01*
X495786D01*
Y6190D01*
X495883D01*
Y6158D01*
X495979D01*
Y6126D01*
X496108D01*
Y6094D01*
X496270D01*
Y6061D01*
X521789D01*
Y6029D01*
X521821D01*
Y6061D01*
X521853D01*
Y6029D01*
X522079D01*
Y5997D01*
X522208D01*
Y5965D01*
X522305D01*
Y5932D01*
X522402D01*
Y5900D01*
X522499D01*
Y5868D01*
X522563D01*
Y5835D01*
X522628D01*
Y5803D01*
X522692D01*
Y5771D01*
X522757D01*
Y5739D01*
X522789D01*
Y5706D01*
X522854D01*
Y5674D01*
X522886D01*
Y5642D01*
X522950D01*
Y5610D01*
X522983D01*
Y5577D01*
X523015D01*
Y5545D01*
X523047D01*
Y5513D01*
X523112D01*
Y5481D01*
X523144D01*
Y5448D01*
X523176D01*
Y5416D01*
X523208D01*
Y5384D01*
X523241D01*
Y5352D01*
X523273D01*
Y5319D01*
Y5287D01*
X523305D01*
Y5255D01*
X523338D01*
Y5223D01*
X523370D01*
Y5190D01*
X523402D01*
Y5158D01*
Y5126D01*
X523434D01*
Y5094D01*
X523466D01*
Y5061D01*
Y5029D01*
X523499D01*
Y4997D01*
X523531D01*
Y4964D01*
Y4932D01*
X523563D01*
Y4900D01*
Y4868D01*
X523596D01*
Y4835D01*
Y4803D01*
X523628D01*
Y4771D01*
Y4739D01*
Y4706D01*
X523660D01*
Y4674D01*
Y4642D01*
X523692D01*
Y4610D01*
Y4577D01*
Y4545D01*
X523725D01*
Y4513D01*
Y4481D01*
Y4448D01*
Y4416D01*
X523757D01*
Y4384D01*
Y4352D01*
Y4319D01*
Y4287D01*
Y4255D01*
X523789D01*
Y4222D01*
Y4190D01*
Y4158D01*
Y4126D01*
Y4093D01*
Y4061D01*
Y4029D01*
Y3997D01*
Y3964D01*
Y3932D01*
Y3900D01*
Y3867D01*
Y3835D01*
Y3803D01*
Y3771D01*
Y3739D01*
Y3706D01*
Y3674D01*
Y3642D01*
X523757D01*
Y3609D01*
Y3577D01*
Y3545D01*
Y3513D01*
Y3480D01*
X523725D01*
Y3448D01*
Y3416D01*
Y3384D01*
Y3351D01*
X523692D01*
Y3319D01*
Y3287D01*
Y3255D01*
X523660D01*
Y3222D01*
Y3190D01*
Y3158D01*
X523628D01*
Y3125D01*
Y3093D01*
X523596D01*
Y3061D01*
Y3029D01*
X523563D01*
Y2997D01*
Y2964D01*
X523531D01*
Y2932D01*
Y2900D01*
X523499D01*
Y2867D01*
Y2835D01*
X523466D01*
Y2803D01*
X523434D01*
Y2771D01*
Y2738D01*
X523402D01*
Y2706D01*
X523370D01*
Y2674D01*
X523338D01*
Y2642D01*
X523305D01*
Y2609D01*
Y2577D01*
X523273D01*
Y2545D01*
X523241D01*
Y2513D01*
X523208D01*
Y2480D01*
X523176D01*
Y2448D01*
X523144D01*
Y2416D01*
X523112D01*
Y2383D01*
X523079D01*
Y2351D01*
X523047D01*
Y2319D01*
X522983D01*
Y2287D01*
X522950D01*
Y2254D01*
X522918D01*
Y2222D01*
X522854D01*
Y2190D01*
X522821D01*
Y2158D01*
X522757D01*
Y2125D01*
X522692D01*
Y2093D01*
X522660D01*
Y2061D01*
X522563D01*
Y2029D01*
X522499D01*
Y1996D01*
X522434D01*
Y1964D01*
X522337D01*
Y1932D01*
X522241D01*
Y1900D01*
X522112D01*
Y1867D01*
X521918D01*
Y1835D01*
X505174D01*
Y1803D01*
X504981D01*
Y1770D01*
X504851D01*
Y1738D01*
X504722D01*
Y1706D01*
X504658D01*
Y1674D01*
X504561D01*
Y1641D01*
X504497D01*
Y1609D01*
X504432D01*
Y1577D01*
X504367D01*
Y1545D01*
X504303D01*
Y1512D01*
X504271D01*
Y1480D01*
X504206D01*
Y1448D01*
X504174D01*
Y1416D01*
X504142D01*
Y1383D01*
X504077D01*
Y1351D01*
X504045D01*
Y1319D01*
X504013D01*
Y1287D01*
X503980D01*
Y1254D01*
X503948D01*
Y1222D01*
X503916D01*
Y1190D01*
X503884D01*
Y1158D01*
X503851D01*
Y1125D01*
X503819D01*
Y1093D01*
X503787D01*
Y1061D01*
X503755D01*
Y1029D01*
X503722D01*
Y996D01*
Y964D01*
X503690D01*
Y932D01*
X503658D01*
Y900D01*
Y867D01*
X503625D01*
Y835D01*
X503593D01*
Y803D01*
Y770D01*
X503561D01*
Y738D01*
Y706D01*
X503529D01*
Y674D01*
Y641D01*
X503497D01*
Y609D01*
Y577D01*
X503464D01*
Y545D01*
Y512D01*
X503432D01*
Y480D01*
Y448D01*
Y416D01*
X503400D01*
Y383D01*
Y351D01*
Y319D01*
X503367D01*
Y286D01*
Y254D01*
Y222D01*
Y190D01*
X503335D01*
Y157D01*
Y125D01*
Y93D01*
Y61D01*
Y28D01*
Y-4D01*
X503303D01*
Y-36D01*
Y-68D01*
Y-101D01*
Y-133D01*
Y-165D01*
Y-197D01*
Y-230D01*
Y-262D01*
Y-294D01*
Y-326D01*
Y-359D01*
Y-391D01*
Y-423D01*
Y-455D01*
Y-488D01*
Y-520D01*
X503335D01*
Y-552D01*
Y-585D01*
Y-617D01*
Y-649D01*
Y-681D01*
Y-714D01*
X503367D01*
Y-746D01*
Y-778D01*
Y-810D01*
Y-843D01*
X503400D01*
Y-875D01*
Y-907D01*
Y-939D01*
X503432D01*
Y-972D01*
Y-1004D01*
Y-1036D01*
X503464D01*
Y-1068D01*
Y-1101D01*
X503497D01*
Y-1133D01*
Y-1165D01*
X503529D01*
Y-1198D01*
Y-1230D01*
X503561D01*
Y-1262D01*
Y-1294D01*
X503593D01*
Y-1327D01*
Y-1359D01*
X503625D01*
Y-1391D01*
X503658D01*
Y-1423D01*
Y-1456D01*
X503690D01*
Y-1488D01*
X503722D01*
Y-1520D01*
X503755D01*
Y-1552D01*
Y-1585D01*
X503787D01*
Y-1617D01*
X503819D01*
Y-1649D01*
X503851D01*
Y-1681D01*
X503884D01*
Y-1714D01*
X503916D01*
Y-1746D01*
X503948D01*
Y-1778D01*
X503980D01*
Y-1811D01*
X504013D01*
Y-1843D01*
X504045D01*
Y-1875D01*
X504109D01*
Y-1907D01*
X504142D01*
Y-1940D01*
X504174D01*
Y-1972D01*
X504239D01*
Y-2004D01*
X504271D01*
Y-2036D01*
X504335D01*
Y-2069D01*
X504400D01*
Y-2101D01*
X504432D01*
Y-2133D01*
X504497D01*
Y-2165D01*
X504593D01*
Y-2198D01*
X504658D01*
Y-2230D01*
X504755D01*
Y-2262D01*
X504851D01*
Y-2294D01*
X504981D01*
Y-2327D01*
X505206D01*
Y-2359D01*
X511401D01*
Y-2391D01*
X511562D01*
Y-2424D01*
X511691D01*
Y-2456D01*
X511788D01*
Y-2488D01*
X511884D01*
Y-2520D01*
X511981D01*
Y-2553D01*
X512046D01*
Y-2585D01*
X512110D01*
Y-2617D01*
X512175D01*
Y-2649D01*
X512239D01*
Y-2682D01*
X512272D01*
Y-2714D01*
X512336D01*
Y-2746D01*
X512368D01*
Y-2778D01*
X512401D01*
Y-2811D01*
X512465D01*
Y-2843D01*
X512498D01*
Y-2875D01*
X512530D01*
Y-2907D01*
X512562D01*
Y-2940D01*
X512594D01*
Y-2972D01*
X512627D01*
Y-3004D01*
X512659D01*
Y-3036D01*
X512691D01*
Y-3069D01*
X512723D01*
Y-3101D01*
X512756D01*
Y-3133D01*
X512788D01*
Y-3165D01*
X512820D01*
Y-3198D01*
Y-3230D01*
X512852D01*
Y-3262D01*
X512885D01*
Y-3295D01*
X512917D01*
Y-3327D01*
Y-3359D01*
X512949D01*
Y-3391D01*
Y-3424D01*
X512981D01*
Y-3456D01*
X513014D01*
Y-3488D01*
Y-3520D01*
X513046D01*
Y-3553D01*
Y-3585D01*
X513078D01*
Y-3617D01*
Y-3650D01*
Y-3682D01*
X513110D01*
Y-3714D01*
Y-3746D01*
X513143D01*
Y-3779D01*
Y-3811D01*
Y-3843D01*
X513175D01*
Y-3875D01*
Y-3907D01*
Y-3940D01*
Y-3972D01*
X513207D01*
Y-4004D01*
Y-4037D01*
Y-4069D01*
Y-4101D01*
Y-4133D01*
X513239D01*
Y-4166D01*
Y-4198D01*
Y-4230D01*
Y-4262D01*
Y-4295D01*
Y-4327D01*
Y-4359D01*
Y-4391D01*
Y-4424D01*
Y-4456D01*
Y-4488D01*
Y-4521D01*
Y-4553D01*
Y-4585D01*
Y-4617D01*
Y-4650D01*
Y-4682D01*
Y-4714D01*
Y-4746D01*
Y-4779D01*
Y-4811D01*
X513207D01*
Y-4843D01*
Y-4875D01*
Y-4908D01*
Y-4940D01*
Y-4972D01*
X513175D01*
Y-5004D01*
Y-5037D01*
Y-5069D01*
X513143D01*
Y-5101D01*
Y-5133D01*
Y-5166D01*
X513110D01*
Y-5198D01*
Y-5230D01*
Y-5263D01*
X513078D01*
Y-5295D01*
Y-5327D01*
X513046D01*
Y-5359D01*
Y-5392D01*
X513014D01*
Y-5424D01*
Y-5456D01*
X512981D01*
Y-5488D01*
Y-5521D01*
X512949D01*
Y-5553D01*
Y-5585D01*
X512917D01*
Y-5617D01*
X512885D01*
Y-5650D01*
Y-5682D01*
X512852D01*
Y-5714D01*
X512820D01*
Y-5746D01*
X512788D01*
Y-5779D01*
X512756D01*
Y-5811D01*
Y-5843D01*
X512723D01*
Y-5875D01*
X512691D01*
Y-5908D01*
X512659D01*
Y-5940D01*
X512627D01*
Y-5972D01*
X512594D01*
Y-6005D01*
X512562D01*
Y-6037D01*
X512530D01*
Y-6069D01*
X512465D01*
Y-6101D01*
X512433D01*
Y-6134D01*
X512401D01*
Y-6166D01*
X512336D01*
Y-6198D01*
X512304D01*
Y-6230D01*
X512239D01*
Y-6263D01*
X512207D01*
Y-6295D01*
X512143D01*
Y-6327D01*
X512078D01*
Y-6359D01*
X512014D01*
Y-6392D01*
X511949D01*
Y-6424D01*
X511852D01*
Y-6456D01*
X511756D01*
Y-6488D01*
X511659D01*
Y-6521D01*
X511497D01*
Y-6553D01*
X511272D01*
Y-6585D01*
X511207D01*
Y-6553D01*
X511175D01*
Y-6585D01*
X501496D01*
Y-6553D01*
X501464D01*
Y-6585D01*
X501141D01*
Y-6617D01*
X500980D01*
Y-6650D01*
X500851D01*
Y-6682D01*
X500754D01*
Y-6714D01*
X500690D01*
Y-6747D01*
X500593D01*
Y-6779D01*
X500528D01*
Y-6811D01*
X500464D01*
Y-6843D01*
X500432D01*
Y-6876D01*
X500367D01*
Y-6908D01*
X500303D01*
Y-6940D01*
X500270D01*
Y-6972D01*
X500206D01*
Y-7005D01*
X500174D01*
Y-7037D01*
X500141D01*
Y-7069D01*
X500109D01*
Y-7102D01*
X500044D01*
Y-7134D01*
X500012D01*
Y-7166D01*
X499980D01*
Y-7198D01*
X499948D01*
Y-7231D01*
X499915D01*
Y-7263D01*
X499883D01*
Y-7295D01*
Y-7327D01*
X499851D01*
Y-7360D01*
X499819D01*
Y-7392D01*
X499786D01*
Y-7424D01*
X499754D01*
Y-7456D01*
Y-7489D01*
X499722D01*
Y-7521D01*
X499690D01*
Y-7553D01*
Y-7585D01*
X499657D01*
Y-7618D01*
X499625D01*
Y-7650D01*
Y-7682D01*
X499593D01*
Y-7714D01*
Y-7747D01*
X499560D01*
Y-7779D01*
Y-7811D01*
X499528D01*
Y-7843D01*
Y-7876D01*
X499496D01*
Y-7908D01*
Y-7940D01*
Y-7972D01*
X499464D01*
Y-8005D01*
Y-8037D01*
Y-8069D01*
X499432D01*
Y-8102D01*
Y-8134D01*
Y-8166D01*
X499399D01*
Y-8198D01*
Y-8231D01*
Y-8263D01*
Y-8295D01*
Y-8327D01*
X499367D01*
Y-8360D01*
Y-8392D01*
Y-8424D01*
Y-8456D01*
Y-8489D01*
Y-8521D01*
Y-8553D01*
Y-8585D01*
Y-8618D01*
Y-8650D01*
Y-8682D01*
Y-8715D01*
Y-8747D01*
Y-8779D01*
Y-8811D01*
Y-8844D01*
Y-8876D01*
Y-8908D01*
Y-8940D01*
Y-8973D01*
Y-9005D01*
X499399D01*
Y-9037D01*
Y-9069D01*
Y-9102D01*
Y-9134D01*
Y-9166D01*
X499432D01*
Y-9199D01*
Y-9231D01*
Y-9263D01*
X499464D01*
Y-9295D01*
Y-9328D01*
Y-9360D01*
X499496D01*
Y-9392D01*
Y-9424D01*
Y-9457D01*
X499528D01*
Y-9489D01*
Y-9521D01*
X499560D01*
Y-9553D01*
Y-9586D01*
X499593D01*
Y-9618D01*
Y-9650D01*
X499625D01*
Y-9682D01*
Y-9715D01*
X499657D01*
Y-9747D01*
Y-9779D01*
X499690D01*
Y-9811D01*
X499722D01*
Y-9844D01*
Y-9876D01*
X499754D01*
Y-9908D01*
X499786D01*
Y-9940D01*
X499819D01*
Y-9973D01*
Y-10005D01*
X499851D01*
Y-10037D01*
X499883D01*
Y-10069D01*
X499915D01*
Y-10102D01*
X499948D01*
Y-10134D01*
X499980D01*
Y-10166D01*
X500012D01*
Y-10199D01*
X500044D01*
Y-10231D01*
X500077D01*
Y-10263D01*
X500109D01*
Y-10295D01*
X500174D01*
Y-10328D01*
X500206D01*
Y-10360D01*
X500238D01*
Y-10392D01*
X500303D01*
Y-10424D01*
X500335D01*
Y-10457D01*
X500399D01*
Y-10489D01*
X500464D01*
Y-10521D01*
X500528D01*
Y-10554D01*
X500593D01*
Y-10586D01*
X500657D01*
Y-10618D01*
X500754D01*
Y-10650D01*
X500819D01*
Y-10683D01*
X500948D01*
Y-10715D01*
X501109D01*
Y-10747D01*
X501399D01*
Y-10779D01*
X508078D01*
Y-10812D01*
X508239D01*
Y-10844D01*
X508336D01*
Y-10876D01*
X508432D01*
Y-10908D01*
X508529D01*
Y-10941D01*
X508626D01*
Y-10973D01*
X508691D01*
Y-11005D01*
X508755D01*
Y-11037D01*
X508787D01*
Y-11070D01*
X508852D01*
Y-11102D01*
X508916D01*
Y-11134D01*
X508949D01*
Y-11167D01*
X509013D01*
Y-11199D01*
X509046D01*
Y-11231D01*
X509078D01*
Y-11263D01*
X509110D01*
Y-11295D01*
X509174D01*
Y-11328D01*
X509207D01*
Y-11360D01*
X509239D01*
Y-11392D01*
X509271D01*
Y-11425D01*
X509304D01*
Y-11457D01*
X509336D01*
Y-11489D01*
Y-11521D01*
X509368D01*
Y-11554D01*
X509400D01*
Y-11586D01*
X509433D01*
Y-11618D01*
X509465D01*
Y-11650D01*
Y-11683D01*
X509497D01*
Y-11715D01*
X509529D01*
Y-11747D01*
Y-11779D01*
X509562D01*
Y-11812D01*
X509594D01*
Y-11844D01*
Y-11876D01*
X509626D01*
Y-11908D01*
Y-11941D01*
X509658D01*
Y-11973D01*
Y-12005D01*
X509691D01*
Y-12037D01*
Y-12070D01*
X509723D01*
Y-12102D01*
Y-12134D01*
Y-12167D01*
X509755D01*
Y-12199D01*
Y-12231D01*
Y-12263D01*
X509788D01*
Y-12296D01*
Y-12328D01*
Y-12360D01*
X509820D01*
Y-12392D01*
Y-12425D01*
Y-12457D01*
Y-12489D01*
Y-12521D01*
Y-12554D01*
X509852D01*
Y-12586D01*
Y-12618D01*
Y-12651D01*
Y-12683D01*
Y-12715D01*
Y-12747D01*
Y-12780D01*
Y-12812D01*
Y-12844D01*
X509884D01*
Y-12876D01*
Y-12909D01*
X509852D01*
Y-12941D01*
Y-12973D01*
Y-13005D01*
Y-13038D01*
Y-13070D01*
Y-13102D01*
Y-13134D01*
Y-13167D01*
Y-13199D01*
Y-13231D01*
X509820D01*
Y-13263D01*
Y-13296D01*
Y-13328D01*
Y-13360D01*
Y-13393D01*
X509788D01*
Y-13425D01*
Y-13457D01*
Y-13489D01*
X509755D01*
Y-13522D01*
Y-13554D01*
Y-13586D01*
X509723D01*
Y-13618D01*
Y-13651D01*
Y-13683D01*
X509691D01*
Y-13715D01*
Y-13747D01*
Y-13780D01*
X509658D01*
Y-13812D01*
Y-13844D01*
X509626D01*
Y-13876D01*
Y-13909D01*
X509594D01*
Y-13941D01*
Y-13973D01*
X509562D01*
Y-14006D01*
X509529D01*
Y-14038D01*
Y-14070D01*
X509497D01*
Y-14102D01*
X509465D01*
Y-14134D01*
Y-14167D01*
X509433D01*
Y-14199D01*
X509400D01*
Y-14231D01*
X509368D01*
Y-14264D01*
Y-14296D01*
X509336D01*
Y-14328D01*
X509304D01*
Y-14360D01*
X509271D01*
Y-14393D01*
X509239D01*
Y-14425D01*
X509207D01*
Y-14457D01*
X509174D01*
Y-14489D01*
X509142D01*
Y-14522D01*
X509110D01*
Y-14554D01*
X509078D01*
Y-14586D01*
X509046D01*
Y-14618D01*
X508981D01*
Y-14651D01*
X508949D01*
Y-14683D01*
X508916D01*
Y-14715D01*
X508852D01*
Y-14748D01*
X508820D01*
Y-14780D01*
X508755D01*
Y-14812D01*
X508691D01*
Y-14844D01*
X508626D01*
Y-14877D01*
X508562D01*
Y-14909D01*
X508465D01*
Y-14941D01*
X508336D01*
Y-14973D01*
X485107D01*
Y-15006D01*
X485043D01*
Y-15038D01*
X485010D01*
Y-15070D01*
X484978D01*
Y-15102D01*
X484946D01*
Y-15135D01*
Y-15167D01*
X484914D01*
Y-15199D01*
Y-15231D01*
Y-15264D01*
Y-15296D01*
Y-15328D01*
Y-15360D01*
Y-15393D01*
Y-15425D01*
Y-15457D01*
Y-15489D01*
Y-15522D01*
Y-15554D01*
Y-15586D01*
Y-15619D01*
Y-15651D01*
Y-15683D01*
Y-15715D01*
Y-15748D01*
Y-15780D01*
Y-15812D01*
Y-15844D01*
Y-15877D01*
Y-15909D01*
Y-15941D01*
Y-15973D01*
Y-16006D01*
Y-16038D01*
Y-16070D01*
Y-16103D01*
Y-16135D01*
Y-16167D01*
Y-16199D01*
Y-16232D01*
Y-16264D01*
Y-16296D01*
Y-16328D01*
Y-16361D01*
Y-16393D01*
Y-16425D01*
Y-16457D01*
Y-16490D01*
Y-16522D01*
Y-16554D01*
Y-16586D01*
Y-16619D01*
Y-16651D01*
Y-16683D01*
Y-16715D01*
Y-16748D01*
Y-16780D01*
Y-16812D01*
Y-16845D01*
Y-16877D01*
Y-16909D01*
Y-16941D01*
Y-16974D01*
Y-17006D01*
Y-17038D01*
Y-17070D01*
Y-17103D01*
Y-17135D01*
Y-17167D01*
Y-17199D01*
Y-17232D01*
Y-17264D01*
Y-17296D01*
Y-17328D01*
Y-17361D01*
Y-17393D01*
Y-17425D01*
Y-17458D01*
Y-17490D01*
Y-17522D01*
Y-17554D01*
Y-17586D01*
Y-17619D01*
Y-17651D01*
Y-17683D01*
Y-17716D01*
Y-17748D01*
Y-17780D01*
Y-17812D01*
Y-17845D01*
Y-17877D01*
Y-17909D01*
Y-17941D01*
Y-17974D01*
Y-18006D01*
Y-18038D01*
Y-18070D01*
Y-18103D01*
Y-18135D01*
Y-18167D01*
Y-18200D01*
Y-18232D01*
Y-18264D01*
Y-18296D01*
Y-18329D01*
Y-18361D01*
X484881D01*
Y-18393D01*
Y-18425D01*
X484849D01*
Y-18458D01*
Y-18490D01*
X484817D01*
Y-18522D01*
X484752D01*
Y-18554D01*
X484688D01*
Y-18587D01*
X478526D01*
Y-18554D01*
X478429D01*
Y-18522D01*
X478397D01*
Y-18490D01*
X478365D01*
Y-18458D01*
X478332D01*
Y-18425D01*
Y-18393D01*
X478300D01*
Y-18361D01*
Y-18329D01*
Y-18296D01*
Y-18264D01*
Y-18232D01*
Y-18200D01*
Y-18167D01*
Y-18135D01*
Y-18103D01*
Y-18070D01*
Y-18038D01*
Y-18006D01*
Y-17974D01*
Y-17941D01*
Y-17909D01*
Y-17877D01*
Y-17845D01*
Y-17812D01*
Y-17780D01*
Y-17748D01*
Y-17716D01*
Y-17683D01*
Y-17651D01*
Y-17619D01*
Y-17586D01*
Y-17554D01*
Y-17522D01*
Y-17490D01*
Y-17458D01*
Y-17425D01*
Y-17393D01*
Y-17361D01*
Y-17328D01*
Y-17296D01*
Y-17264D01*
Y-17232D01*
Y-17199D01*
Y-17167D01*
Y-17135D01*
Y-17103D01*
Y-17070D01*
Y-17038D01*
Y-17006D01*
Y-16974D01*
Y-16941D01*
Y-16909D01*
Y-16877D01*
Y-16845D01*
Y-16812D01*
Y-16780D01*
Y-16748D01*
Y-16715D01*
Y-16683D01*
Y-16651D01*
Y-16619D01*
Y-16586D01*
Y-16554D01*
Y-16522D01*
Y-16490D01*
Y-16457D01*
Y-16425D01*
X478268D01*
Y-16393D01*
Y-16361D01*
Y-16328D01*
X478235D01*
Y-16296D01*
Y-16264D01*
X478203D01*
Y-16232D01*
X478139D01*
Y-16199D01*
X478042D01*
Y-16167D01*
X477945D01*
Y-16199D01*
X477848D01*
Y-16232D01*
X477816D01*
Y-16264D01*
X477784D01*
Y-16296D01*
X477752D01*
Y-16328D01*
X477719D01*
Y-16361D01*
Y-16393D01*
Y-16425D01*
Y-16457D01*
X477687D01*
Y-16490D01*
Y-16522D01*
Y-16554D01*
Y-16586D01*
Y-16619D01*
Y-16651D01*
Y-16683D01*
Y-16715D01*
Y-16748D01*
Y-16780D01*
Y-16812D01*
Y-16845D01*
Y-16877D01*
Y-16909D01*
Y-16941D01*
Y-16974D01*
Y-17006D01*
Y-17038D01*
Y-17070D01*
Y-17103D01*
Y-17135D01*
Y-17167D01*
Y-17199D01*
Y-17232D01*
Y-17264D01*
Y-17296D01*
Y-17328D01*
Y-17361D01*
Y-17393D01*
Y-17425D01*
Y-17458D01*
Y-17490D01*
Y-17522D01*
Y-17554D01*
Y-17586D01*
Y-17619D01*
Y-17651D01*
Y-17683D01*
Y-17716D01*
Y-17748D01*
Y-17780D01*
Y-17812D01*
Y-17845D01*
Y-17877D01*
Y-17909D01*
Y-17941D01*
Y-17974D01*
Y-18006D01*
Y-18038D01*
Y-18070D01*
Y-18103D01*
Y-18135D01*
Y-18167D01*
Y-18200D01*
Y-18232D01*
Y-18264D01*
Y-18296D01*
Y-18329D01*
Y-18361D01*
Y-18393D01*
Y-18425D01*
X477655D01*
Y-18458D01*
X477623D01*
Y-18490D01*
X477590D01*
Y-18522D01*
X477558D01*
Y-18554D01*
X477461D01*
Y-18587D01*
X474299D01*
Y-18554D01*
X474235D01*
Y-18522D01*
X474170D01*
Y-18490D01*
X474138D01*
Y-18458D01*
Y-18425D01*
X474106D01*
Y-18393D01*
Y-18361D01*
Y-18329D01*
X474074D01*
Y-18296D01*
Y-18264D01*
Y-18232D01*
Y-18200D01*
Y-18167D01*
Y-18135D01*
Y-18103D01*
Y-18070D01*
Y-18038D01*
Y-18006D01*
Y-17974D01*
Y-17941D01*
Y-17909D01*
Y-17877D01*
Y-17845D01*
Y-17812D01*
Y-17780D01*
Y-17748D01*
Y-17716D01*
Y-17683D01*
Y-17651D01*
Y-17619D01*
Y-17586D01*
Y-17554D01*
Y-17522D01*
Y-17490D01*
Y-17458D01*
Y-17425D01*
Y-17393D01*
Y-17361D01*
Y-17328D01*
Y-17296D01*
Y-17264D01*
Y-17232D01*
Y-17199D01*
Y-17167D01*
Y-17135D01*
Y-17103D01*
Y-17070D01*
Y-17038D01*
Y-17006D01*
Y-16974D01*
Y-16941D01*
Y-16909D01*
Y-16877D01*
Y-16845D01*
Y-16812D01*
Y-16780D01*
Y-16748D01*
Y-16715D01*
Y-16683D01*
Y-16651D01*
Y-16619D01*
Y-16586D01*
Y-16554D01*
Y-16522D01*
Y-16490D01*
Y-16457D01*
Y-16425D01*
Y-16393D01*
Y-16361D01*
Y-16328D01*
Y-16296D01*
Y-16264D01*
Y-16232D01*
Y-16199D01*
Y-16167D01*
Y-16135D01*
Y-16103D01*
Y-16070D01*
Y-16038D01*
Y-16006D01*
Y-15973D01*
Y-15941D01*
Y-15909D01*
Y-15877D01*
Y-15844D01*
Y-15812D01*
Y-15780D01*
Y-15748D01*
Y-15715D01*
X474106D01*
Y-15683D01*
X474074D01*
Y-15651D01*
Y-15619D01*
Y-15586D01*
Y-15554D01*
Y-15522D01*
Y-15489D01*
Y-15457D01*
Y-15425D01*
Y-15393D01*
X474041D01*
Y-15360D01*
Y-15328D01*
X474009D01*
Y-15296D01*
Y-15264D01*
X473977D01*
Y-15231D01*
Y-15199D01*
X473945D01*
Y-15167D01*
X473912D01*
Y-15135D01*
X473880D01*
Y-15102D01*
X473848D01*
Y-15070D01*
X473783D01*
Y-15038D01*
X473719D01*
Y-15006D01*
X473622D01*
Y-14973D01*
X473364D01*
Y-15006D01*
X473267D01*
Y-15038D01*
X473203D01*
Y-15070D01*
X473138D01*
Y-15102D01*
X473106D01*
Y-15135D01*
X473074D01*
Y-15167D01*
X473041D01*
Y-15199D01*
X473009D01*
Y-15231D01*
X472977D01*
Y-15264D01*
Y-15296D01*
X472944D01*
Y-15328D01*
Y-15360D01*
X472912D01*
Y-15393D01*
Y-15425D01*
Y-15457D01*
Y-15489D01*
Y-15522D01*
Y-15554D01*
X472880D01*
Y-15586D01*
X472912D01*
Y-15619D01*
Y-15651D01*
X472880D01*
Y-15683D01*
X472912D01*
Y-15715D01*
Y-15748D01*
Y-15780D01*
Y-15812D01*
Y-15844D01*
Y-15877D01*
Y-15909D01*
Y-15941D01*
Y-15973D01*
Y-16006D01*
Y-16038D01*
Y-16070D01*
Y-16103D01*
Y-16135D01*
Y-16167D01*
Y-16199D01*
Y-16232D01*
Y-16264D01*
Y-16296D01*
Y-16328D01*
Y-16361D01*
Y-16393D01*
Y-16425D01*
Y-16457D01*
Y-16490D01*
Y-16522D01*
Y-16554D01*
Y-16586D01*
Y-16619D01*
Y-16651D01*
Y-16683D01*
Y-16715D01*
Y-16748D01*
Y-16780D01*
Y-16812D01*
Y-16845D01*
Y-16877D01*
Y-16909D01*
Y-16941D01*
Y-16974D01*
Y-17006D01*
Y-17038D01*
Y-17070D01*
X472880D01*
Y-17103D01*
Y-17135D01*
Y-17167D01*
Y-17199D01*
X472848D01*
Y-17232D01*
X472816D01*
Y-17264D01*
X472783D01*
Y-17296D01*
X472751D01*
Y-17328D01*
X472654D01*
Y-17361D01*
X470718D01*
Y-17328D01*
X470622D01*
Y-17296D01*
X470589D01*
Y-17264D01*
X470557D01*
Y-17232D01*
X470525D01*
Y-17199D01*
X470493D01*
Y-17167D01*
Y-17135D01*
Y-17103D01*
X470460D01*
Y-17070D01*
Y-17038D01*
Y-17006D01*
Y-16974D01*
Y-16941D01*
Y-16909D01*
Y-16877D01*
Y-16845D01*
Y-16812D01*
Y-16780D01*
Y-16748D01*
Y-16715D01*
Y-16683D01*
Y-16651D01*
Y-16619D01*
Y-16586D01*
Y-16554D01*
Y-16522D01*
Y-16490D01*
Y-16457D01*
Y-16425D01*
Y-16393D01*
Y-16361D01*
Y-16328D01*
Y-16296D01*
Y-16264D01*
Y-16232D01*
Y-16199D01*
Y-16167D01*
Y-16135D01*
Y-16103D01*
Y-16070D01*
Y-16038D01*
Y-16006D01*
Y-15973D01*
Y-15941D01*
Y-15909D01*
Y-15877D01*
Y-15844D01*
Y-15812D01*
Y-15780D01*
Y-15748D01*
Y-15715D01*
Y-15683D01*
Y-15651D01*
Y-15619D01*
Y-15586D01*
Y-15554D01*
Y-15522D01*
Y-15489D01*
Y-15457D01*
X470493D01*
Y-15425D01*
Y-15393D01*
X470460D01*
Y-15360D01*
X470493D01*
Y-15328D01*
X470460D01*
Y-15296D01*
Y-15264D01*
Y-15231D01*
Y-15199D01*
Y-15167D01*
Y-15135D01*
X470428D01*
Y-15102D01*
Y-15070D01*
X470396D01*
Y-15038D01*
X470331D01*
Y-15006D01*
X470267D01*
Y-14973D01*
X465266D01*
Y-15006D01*
X465202D01*
Y-15038D01*
X465169D01*
Y-15070D01*
X465137D01*
Y-15102D01*
X465105D01*
Y-15135D01*
Y-15167D01*
X465073D01*
Y-15199D01*
Y-15231D01*
Y-15264D01*
Y-15296D01*
Y-15328D01*
Y-15360D01*
Y-15393D01*
Y-15425D01*
Y-15457D01*
Y-15489D01*
Y-15522D01*
Y-15554D01*
Y-15586D01*
Y-15619D01*
Y-15651D01*
Y-15683D01*
Y-15715D01*
Y-15748D01*
Y-15780D01*
Y-15812D01*
Y-15844D01*
Y-15877D01*
Y-15909D01*
Y-15941D01*
Y-15973D01*
Y-16006D01*
Y-16038D01*
Y-16070D01*
Y-16103D01*
Y-16135D01*
Y-16167D01*
Y-16199D01*
Y-16232D01*
Y-16264D01*
Y-16296D01*
Y-16328D01*
Y-16361D01*
Y-16393D01*
Y-16425D01*
Y-16457D01*
Y-16490D01*
Y-16522D01*
Y-16554D01*
Y-16586D01*
Y-16619D01*
Y-16651D01*
Y-16683D01*
Y-16715D01*
Y-16748D01*
Y-16780D01*
Y-16812D01*
Y-16845D01*
Y-16877D01*
Y-16909D01*
Y-16941D01*
Y-16974D01*
Y-17006D01*
Y-17038D01*
Y-17070D01*
Y-17103D01*
Y-17135D01*
Y-17167D01*
Y-17199D01*
Y-17232D01*
Y-17264D01*
Y-17296D01*
Y-17328D01*
Y-17361D01*
Y-17393D01*
Y-17425D01*
Y-17458D01*
Y-17490D01*
Y-17522D01*
Y-17554D01*
Y-17586D01*
Y-17619D01*
Y-17651D01*
Y-17683D01*
Y-17716D01*
Y-17748D01*
Y-17780D01*
Y-17812D01*
Y-17845D01*
Y-17877D01*
Y-17909D01*
Y-17941D01*
Y-17974D01*
X460266D01*
Y-17941D01*
Y-17909D01*
Y-17877D01*
Y-17845D01*
Y-17812D01*
Y-17780D01*
Y-17748D01*
Y-17716D01*
Y-17683D01*
Y-17651D01*
Y-17619D01*
Y-17586D01*
Y-17554D01*
Y-17522D01*
Y-17490D01*
Y-17458D01*
Y-17425D01*
Y-17393D01*
Y-17361D01*
Y-17328D01*
Y-17296D01*
Y-17264D01*
Y-17232D01*
Y-17199D01*
Y-17167D01*
Y-17135D01*
Y-17103D01*
Y-17070D01*
Y-17038D01*
Y-17006D01*
Y-16974D01*
Y-16941D01*
Y-16909D01*
Y-16877D01*
Y-16845D01*
Y-16812D01*
Y-16780D01*
Y-16748D01*
Y-16715D01*
Y-16683D01*
Y-16651D01*
Y-16619D01*
Y-16586D01*
Y-16554D01*
Y-16522D01*
Y-16490D01*
Y-16457D01*
Y-16425D01*
Y-16393D01*
Y-16361D01*
Y-16328D01*
Y-16296D01*
Y-16264D01*
Y-16232D01*
Y-16199D01*
Y-16167D01*
Y-16135D01*
Y-16103D01*
Y-16070D01*
Y-16038D01*
Y-16006D01*
Y-15973D01*
Y-15941D01*
Y-15909D01*
Y-15877D01*
Y-15844D01*
Y-15812D01*
Y-15780D01*
Y-15748D01*
Y-15715D01*
Y-15683D01*
Y-15651D01*
Y-15619D01*
Y-15586D01*
Y-15554D01*
Y-15522D01*
Y-15489D01*
Y-15457D01*
Y-15425D01*
Y-15393D01*
Y-15360D01*
Y-15328D01*
Y-15296D01*
Y-15264D01*
Y-15231D01*
Y-15199D01*
Y-15167D01*
Y-15135D01*
Y-15102D01*
Y-15070D01*
X463395D01*
Y-15038D01*
Y-15006D01*
Y-14973D01*
Y-14941D01*
Y-14909D01*
Y-14877D01*
Y-14844D01*
Y-14812D01*
Y-14780D01*
Y-14748D01*
Y-14715D01*
Y-14683D01*
Y-14651D01*
Y-14618D01*
Y-14586D01*
Y-14554D01*
Y-14522D01*
Y-14489D01*
Y-14457D01*
Y-14425D01*
Y-14393D01*
Y-14360D01*
Y-14328D01*
Y-14296D01*
Y-14264D01*
Y-14231D01*
Y-14199D01*
Y-14167D01*
Y-14134D01*
Y-14102D01*
Y-14070D01*
Y-14038D01*
Y-14006D01*
Y-13973D01*
Y-13941D01*
Y-13909D01*
Y-13876D01*
Y-13844D01*
Y-13812D01*
Y-13780D01*
Y-13747D01*
Y-13715D01*
Y-13683D01*
Y-13651D01*
Y-13618D01*
Y-13586D01*
Y-13554D01*
Y-13522D01*
Y-13489D01*
Y-13457D01*
Y-13425D01*
Y-13393D01*
Y-13360D01*
Y-13328D01*
Y-13296D01*
Y-13263D01*
Y-13231D01*
Y-13199D01*
Y-13167D01*
Y-13134D01*
Y-13102D01*
Y-13070D01*
Y-13038D01*
Y-13005D01*
Y-12973D01*
Y-12941D01*
Y-12909D01*
Y-12876D01*
Y-12844D01*
Y-12812D01*
Y-12780D01*
Y-12747D01*
Y-12715D01*
Y-12683D01*
Y-12651D01*
Y-12618D01*
Y-12586D01*
Y-12554D01*
Y-12521D01*
Y-12489D01*
Y-12457D01*
Y-12425D01*
Y-12392D01*
Y-12360D01*
Y-12328D01*
Y-12296D01*
Y-12263D01*
Y-12231D01*
Y-12199D01*
Y-12167D01*
Y-12134D01*
Y-12102D01*
Y-12070D01*
Y-12037D01*
Y-12005D01*
Y-11973D01*
Y-11941D01*
Y-11908D01*
Y-11876D01*
Y-11844D01*
Y-11812D01*
Y-11779D01*
Y-11747D01*
Y-11715D01*
Y-11683D01*
Y-11650D01*
Y-11618D01*
Y-11586D01*
Y-11554D01*
Y-11521D01*
X460266D01*
Y-11489D01*
Y-11457D01*
Y-11425D01*
Y-11392D01*
Y-11360D01*
Y-11328D01*
Y-11295D01*
Y-11263D01*
Y-11231D01*
Y-11199D01*
Y-11167D01*
Y-11134D01*
Y-11102D01*
Y-11070D01*
Y-11037D01*
Y-11005D01*
Y-10973D01*
Y-10941D01*
Y-10908D01*
Y-10876D01*
Y-10844D01*
Y-10812D01*
Y-10779D01*
Y-10747D01*
Y-10715D01*
X463395D01*
Y-10683D01*
Y-10650D01*
Y-10618D01*
Y-10586D01*
Y-10554D01*
Y-10521D01*
Y-10489D01*
Y-10457D01*
Y-10424D01*
Y-10392D01*
Y-10360D01*
Y-10328D01*
Y-10295D01*
Y-10263D01*
Y-10231D01*
Y-10199D01*
Y-10166D01*
Y-10134D01*
Y-10102D01*
Y-10069D01*
Y-10037D01*
Y-10005D01*
Y-9973D01*
Y-9940D01*
Y-9908D01*
Y-9876D01*
Y-9844D01*
Y-9811D01*
Y-9779D01*
Y-9747D01*
Y-9715D01*
Y-9682D01*
Y-9650D01*
Y-9618D01*
Y-9586D01*
Y-9553D01*
Y-9521D01*
Y-9489D01*
Y-9457D01*
Y-9424D01*
Y-9392D01*
Y-9360D01*
Y-9328D01*
Y-9295D01*
Y-9263D01*
Y-9231D01*
Y-9199D01*
Y-9166D01*
Y-9134D01*
Y-9102D01*
Y-9069D01*
Y-9037D01*
Y-9005D01*
Y-8973D01*
Y-8940D01*
Y-8908D01*
Y-8876D01*
Y-8844D01*
Y-8811D01*
Y-8779D01*
Y-8747D01*
Y-8715D01*
Y-8682D01*
Y-8650D01*
Y-8618D01*
Y-8585D01*
Y-8553D01*
Y-8521D01*
Y-8489D01*
Y-8456D01*
Y-8424D01*
Y-8392D01*
Y-8360D01*
Y-8327D01*
Y-8295D01*
Y-8263D01*
Y-8231D01*
Y-8198D01*
Y-8166D01*
Y-8134D01*
Y-8102D01*
Y-8069D01*
Y-8037D01*
Y-8005D01*
Y-7972D01*
Y-7940D01*
Y-7908D01*
Y-7876D01*
Y-7843D01*
Y-7811D01*
Y-7779D01*
Y-7747D01*
Y-7714D01*
Y-7682D01*
Y-7650D01*
Y-7618D01*
Y-7585D01*
Y-7553D01*
Y-7521D01*
Y-7489D01*
Y-7456D01*
Y-7424D01*
Y-7392D01*
Y-7360D01*
Y-7327D01*
Y-7295D01*
Y-7263D01*
Y-7231D01*
Y-7198D01*
Y-7166D01*
X460298D01*
Y-7134D01*
X460266D01*
Y-7102D01*
Y-7069D01*
Y-7037D01*
Y-7005D01*
Y-6972D01*
Y-6940D01*
Y-6908D01*
Y-6876D01*
Y-6843D01*
Y-6811D01*
Y-6779D01*
Y-6747D01*
Y-6714D01*
Y-6682D01*
Y-6650D01*
Y-6617D01*
Y-6585D01*
Y-6553D01*
Y-6521D01*
Y-6488D01*
Y-6456D01*
Y-6424D01*
Y-6392D01*
Y-6359D01*
X463395D01*
Y-6327D01*
Y-6295D01*
Y-6263D01*
Y-6230D01*
Y-6198D01*
Y-6166D01*
Y-6134D01*
Y-6101D01*
Y-6069D01*
Y-6037D01*
Y-6005D01*
Y-5972D01*
Y-5940D01*
Y-5908D01*
Y-5875D01*
Y-5843D01*
Y-5811D01*
Y-5779D01*
Y-5746D01*
Y-5714D01*
Y-5682D01*
Y-5650D01*
Y-5617D01*
Y-5585D01*
Y-5553D01*
Y-5521D01*
Y-5488D01*
Y-5456D01*
Y-5424D01*
Y-5392D01*
Y-5359D01*
Y-5327D01*
Y-5295D01*
Y-5263D01*
Y-5230D01*
Y-5198D01*
Y-5166D01*
Y-5133D01*
Y-5101D01*
Y-5069D01*
Y-5037D01*
Y-5004D01*
Y-4972D01*
Y-4940D01*
Y-4908D01*
Y-4875D01*
Y-4843D01*
Y-4811D01*
Y-4779D01*
Y-4746D01*
Y-4714D01*
Y-4682D01*
Y-4650D01*
Y-4617D01*
Y-4585D01*
Y-4553D01*
Y-4521D01*
Y-4488D01*
Y-4456D01*
Y-4424D01*
Y-4391D01*
Y-4359D01*
Y-4327D01*
Y-4295D01*
Y-4262D01*
Y-4230D01*
Y-4198D01*
Y-4166D01*
Y-4133D01*
Y-4101D01*
Y-4069D01*
Y-4037D01*
Y-4004D01*
Y-3972D01*
Y-3940D01*
Y-3907D01*
Y-3875D01*
Y-3843D01*
Y-3811D01*
Y-3779D01*
Y-3746D01*
Y-3714D01*
Y-3682D01*
Y-3650D01*
Y-3617D01*
Y-3585D01*
Y-3553D01*
Y-3520D01*
Y-3488D01*
Y-3456D01*
Y-3424D01*
Y-3391D01*
Y-3359D01*
Y-3327D01*
Y-3295D01*
Y-3262D01*
Y-3230D01*
Y-3198D01*
Y-3165D01*
Y-3133D01*
Y-3101D01*
Y-3069D01*
Y-3036D01*
Y-3004D01*
Y-2972D01*
Y-2940D01*
Y-2907D01*
Y-2875D01*
Y-2843D01*
Y-2811D01*
Y-2778D01*
X460266D01*
Y-2746D01*
Y-2714D01*
Y-2682D01*
Y-2649D01*
Y-2617D01*
Y-2585D01*
Y-2553D01*
Y-2520D01*
Y-2488D01*
Y-2456D01*
Y-2424D01*
Y-2391D01*
Y-2359D01*
Y-2327D01*
Y-2294D01*
Y-2262D01*
Y-2230D01*
Y-2198D01*
Y-2165D01*
Y-2133D01*
Y-2101D01*
Y-2069D01*
Y-2036D01*
Y-2004D01*
X460298D01*
Y-1972D01*
X463395D01*
Y-1940D01*
Y-1907D01*
Y-1875D01*
Y-1843D01*
Y-1811D01*
Y-1778D01*
Y-1746D01*
Y-1714D01*
Y-1681D01*
Y-1649D01*
Y-1617D01*
Y-1585D01*
Y-1552D01*
Y-1520D01*
Y-1488D01*
Y-1456D01*
Y-1423D01*
Y-1391D01*
Y-1359D01*
Y-1327D01*
Y-1294D01*
Y-1262D01*
Y-1230D01*
Y-1198D01*
Y-1165D01*
Y-1133D01*
Y-1101D01*
Y-1068D01*
Y-1036D01*
Y-1004D01*
Y-972D01*
Y-939D01*
Y-907D01*
Y-875D01*
Y-843D01*
Y-810D01*
Y-778D01*
Y-746D01*
Y-714D01*
Y-681D01*
Y-649D01*
Y-617D01*
Y-585D01*
Y-552D01*
Y-520D01*
Y-488D01*
Y-455D01*
Y-423D01*
Y-391D01*
Y-359D01*
Y-326D01*
Y-294D01*
Y-262D01*
Y-230D01*
Y-197D01*
Y-165D01*
Y-133D01*
Y-101D01*
Y-68D01*
Y-36D01*
Y-4D01*
Y28D01*
Y61D01*
Y93D01*
Y125D01*
Y157D01*
Y190D01*
Y222D01*
Y254D01*
Y286D01*
Y319D01*
Y351D01*
Y383D01*
Y416D01*
Y448D01*
Y480D01*
Y512D01*
Y545D01*
Y577D01*
Y609D01*
Y641D01*
Y674D01*
Y706D01*
Y738D01*
Y770D01*
Y803D01*
Y835D01*
Y867D01*
Y900D01*
Y932D01*
Y964D01*
Y996D01*
Y1029D01*
Y1061D01*
Y1093D01*
Y1125D01*
Y1158D01*
Y1190D01*
Y1222D01*
Y1254D01*
Y1287D01*
Y1319D01*
Y1351D01*
Y1383D01*
Y1416D01*
Y1448D01*
Y1480D01*
Y1512D01*
Y1545D01*
Y1577D01*
X460266D01*
Y1609D01*
Y1641D01*
Y1674D01*
Y1706D01*
Y1738D01*
Y1770D01*
Y1803D01*
Y1835D01*
Y1867D01*
Y1900D01*
Y1932D01*
Y1964D01*
Y1996D01*
Y2029D01*
Y2061D01*
Y2093D01*
Y2125D01*
Y2158D01*
Y2190D01*
Y2222D01*
Y2254D01*
Y2287D01*
Y2319D01*
Y2351D01*
Y2383D01*
Y2416D01*
Y2448D01*
Y2480D01*
Y2513D01*
Y2545D01*
Y2577D01*
Y2609D01*
Y2642D01*
Y2674D01*
Y2706D01*
Y2738D01*
Y2771D01*
Y2803D01*
Y2835D01*
Y2867D01*
Y2900D01*
Y2932D01*
Y2964D01*
Y2997D01*
Y3029D01*
Y3061D01*
Y3093D01*
Y3125D01*
Y3158D01*
Y3190D01*
Y3222D01*
Y3255D01*
Y3287D01*
Y3319D01*
Y3351D01*
Y3384D01*
Y3416D01*
Y3448D01*
Y3480D01*
Y3513D01*
Y3545D01*
Y3577D01*
Y3609D01*
Y3642D01*
Y3674D01*
Y3706D01*
Y3739D01*
Y3771D01*
Y3803D01*
Y3835D01*
Y3867D01*
Y3900D01*
Y3932D01*
Y3964D01*
Y3997D01*
Y4029D01*
Y4061D01*
Y4093D01*
Y4126D01*
Y4158D01*
Y4190D01*
Y4222D01*
Y4255D01*
Y4287D01*
Y4319D01*
Y4352D01*
Y4384D01*
Y4416D01*
Y4448D01*
Y4481D01*
Y4513D01*
Y4545D01*
Y4577D01*
Y4610D01*
Y4642D01*
Y4674D01*
Y4706D01*
Y4739D01*
Y4771D01*
Y4803D01*
Y4835D01*
Y4868D01*
Y4900D01*
Y4932D01*
Y4964D01*
Y4997D01*
Y5029D01*
Y5061D01*
Y5094D01*
Y5126D01*
Y5158D01*
Y5190D01*
Y5223D01*
Y5255D01*
Y5287D01*
Y5319D01*
Y5352D01*
Y5384D01*
Y5416D01*
Y5448D01*
Y5481D01*
Y5513D01*
Y5545D01*
Y5577D01*
Y5610D01*
Y5642D01*
Y5674D01*
Y5706D01*
Y5739D01*
Y5771D01*
Y5803D01*
Y5835D01*
Y5868D01*
Y5900D01*
Y5932D01*
Y5965D01*
Y5997D01*
Y6029D01*
Y6061D01*
Y6094D01*
Y6126D01*
Y6158D01*
Y6190D01*
Y6223D01*
Y6255D01*
Y6287D01*
Y6319D01*
Y6352D01*
Y6384D01*
Y6416D01*
Y6448D01*
Y6481D01*
Y6513D01*
Y6545D01*
Y6577D01*
Y6610D01*
Y6642D01*
Y6674D01*
Y6707D01*
Y6739D01*
Y6771D01*
Y6803D01*
Y6836D01*
Y6868D01*
Y6900D01*
Y6932D01*
Y6965D01*
Y6997D01*
Y7029D01*
Y7062D01*
Y7094D01*
Y7126D01*
Y7158D01*
Y7191D01*
Y7223D01*
Y7255D01*
Y7287D01*
Y7320D01*
Y7352D01*
Y7384D01*
Y7416D01*
Y7449D01*
Y7481D01*
Y7513D01*
Y7545D01*
Y7578D01*
Y7610D01*
Y7642D01*
Y7674D01*
Y7707D01*
Y7739D01*
Y7771D01*
Y7803D01*
Y7836D01*
Y7868D01*
Y7900D01*
Y7932D01*
Y7965D01*
Y7997D01*
Y8029D01*
Y8062D01*
Y8094D01*
Y8126D01*
Y8158D01*
Y8191D01*
Y8223D01*
Y8255D01*
Y8287D01*
Y8320D01*
Y8352D01*
Y8384D01*
Y8416D01*
Y8449D01*
Y8481D01*
Y8513D01*
Y8546D01*
Y8578D01*
Y8610D01*
Y8642D01*
Y8675D01*
Y8707D01*
Y8739D01*
Y8771D01*
Y8804D01*
Y8836D01*
Y8868D01*
Y8900D01*
Y8933D01*
Y8965D01*
Y8997D01*
Y9029D01*
Y9062D01*
Y9094D01*
Y9126D01*
Y9159D01*
Y9191D01*
Y9223D01*
Y9255D01*
Y9287D01*
Y9320D01*
Y9352D01*
Y9384D01*
Y9417D01*
Y9449D01*
Y9481D01*
Y9513D01*
Y9546D01*
Y9578D01*
Y9610D01*
Y9642D01*
Y9675D01*
Y9707D01*
Y9739D01*
Y9771D01*
Y9804D01*
Y9836D01*
Y9868D01*
Y9900D01*
Y9933D01*
Y9965D01*
Y9997D01*
Y10029D01*
Y10062D01*
Y10094D01*
Y10126D01*
Y10159D01*
Y10191D01*
Y10223D01*
Y10255D01*
Y10288D01*
Y10320D01*
Y10352D01*
Y10384D01*
Y10417D01*
Y10449D01*
Y10481D01*
Y10514D01*
Y10546D01*
Y10578D01*
Y10610D01*
Y10643D01*
Y10675D01*
Y10707D01*
Y10739D01*
Y10772D01*
Y10804D01*
Y10836D01*
Y10868D01*
Y10901D01*
Y10933D01*
Y10965D01*
Y10997D01*
Y11030D01*
Y11062D01*
Y11094D01*
Y11126D01*
Y11159D01*
Y11191D01*
Y11223D01*
Y11255D01*
Y11288D01*
Y11320D01*
Y11352D01*
Y11384D01*
Y11417D01*
Y11449D01*
Y11481D01*
Y11514D01*
Y11546D01*
Y11578D01*
Y11610D01*
Y11643D01*
Y11675D01*
Y11707D01*
Y11739D01*
Y11772D01*
Y11804D01*
Y11836D01*
Y11868D01*
Y11901D01*
Y11933D01*
Y11965D01*
Y11998D01*
Y12030D01*
Y12062D01*
Y12094D01*
Y12127D01*
Y12159D01*
Y12191D01*
Y12223D01*
Y12256D01*
Y12288D01*
Y12320D01*
Y12352D01*
Y12385D01*
Y12417D01*
Y12449D01*
Y12481D01*
Y12514D01*
Y12546D01*
Y12578D01*
Y12610D01*
Y12643D01*
Y12675D01*
Y12707D01*
Y12740D01*
Y12772D01*
Y12804D01*
Y12836D01*
Y12869D01*
Y12901D01*
Y12933D01*
Y12965D01*
Y12998D01*
Y13030D01*
Y13062D01*
Y13094D01*
Y13127D01*
Y13159D01*
Y13191D01*
Y13223D01*
Y13256D01*
Y13288D01*
Y13320D01*
Y13352D01*
Y13385D01*
Y13417D01*
Y13449D01*
Y13482D01*
Y13514D01*
Y13546D01*
Y13578D01*
Y13611D01*
Y13643D01*
Y13675D01*
Y13707D01*
Y13740D01*
Y13772D01*
Y13804D01*
Y13836D01*
Y13869D01*
Y13901D01*
Y13933D01*
Y13965D01*
Y13998D01*
Y14030D01*
Y14062D01*
Y14095D01*
Y14127D01*
Y14159D01*
Y14191D01*
Y14224D01*
Y14256D01*
Y14288D01*
Y14320D01*
Y14353D01*
Y14385D01*
Y14417D01*
Y14449D01*
X460298D01*
Y14482D01*
X501012D01*
Y14449D01*
D02*
G37*
G36*
X461750Y-7747D02*
X461911D01*
Y-7779D01*
X462008D01*
Y-7811D01*
X462105D01*
Y-7843D01*
X462169D01*
Y-7876D01*
X462234D01*
Y-7908D01*
X462266D01*
Y-7940D01*
X462330D01*
Y-7972D01*
X462363D01*
Y-8005D01*
X462395D01*
Y-8037D01*
X462427D01*
Y-8069D01*
X462460D01*
Y-8102D01*
X462492D01*
Y-8134D01*
X462524D01*
Y-8166D01*
X462556D01*
Y-8198D01*
X462589D01*
Y-8231D01*
Y-8263D01*
X462621D01*
Y-8295D01*
X462653D01*
Y-8327D01*
Y-8360D01*
X462685D01*
Y-8392D01*
Y-8424D01*
X462718D01*
Y-8456D01*
Y-8489D01*
X462750D01*
Y-8521D01*
Y-8553D01*
Y-8585D01*
X462782D01*
Y-8618D01*
Y-8650D01*
Y-8682D01*
Y-8715D01*
X462814D01*
Y-8747D01*
Y-8779D01*
Y-8811D01*
Y-8844D01*
Y-8876D01*
Y-8908D01*
Y-8940D01*
Y-8973D01*
Y-9005D01*
Y-9037D01*
Y-9069D01*
Y-9102D01*
Y-9134D01*
X462782D01*
Y-9166D01*
Y-9199D01*
Y-9231D01*
Y-9263D01*
X462750D01*
Y-9295D01*
Y-9328D01*
Y-9360D01*
X462718D01*
Y-9392D01*
Y-9424D01*
Y-9457D01*
X462685D01*
Y-9489D01*
Y-9521D01*
X462653D01*
Y-9553D01*
X462621D01*
Y-9586D01*
Y-9618D01*
X462589D01*
Y-9650D01*
X462556D01*
Y-9682D01*
Y-9715D01*
X462524D01*
Y-9747D01*
X462492D01*
Y-9779D01*
X462460D01*
Y-9811D01*
X462427D01*
Y-9844D01*
X462395D01*
Y-9876D01*
X462330D01*
Y-9908D01*
X462298D01*
Y-9940D01*
X462234D01*
Y-9973D01*
X462201D01*
Y-10005D01*
X462137D01*
Y-10037D01*
X462040D01*
Y-10069D01*
X461976D01*
Y-10102D01*
X461846D01*
Y-10134D01*
X461363D01*
Y-10102D01*
X461266D01*
Y-10069D01*
X461169D01*
Y-10037D01*
X461072D01*
Y-10005D01*
X461040D01*
Y-9973D01*
X460975D01*
Y-9940D01*
X460911D01*
Y-9908D01*
X460879D01*
Y-9876D01*
X460846D01*
Y-9844D01*
X460782D01*
Y-9811D01*
X460750D01*
Y-9779D01*
X460717D01*
Y-9747D01*
X460685D01*
Y-9715D01*
Y-9682D01*
X460653D01*
Y-9650D01*
X460620D01*
Y-9618D01*
X460588D01*
Y-9586D01*
Y-9553D01*
X460556D01*
Y-9521D01*
Y-9489D01*
X460524D01*
Y-9457D01*
Y-9424D01*
X460492D01*
Y-9392D01*
Y-9360D01*
X460459D01*
Y-9328D01*
Y-9295D01*
Y-9263D01*
X460427D01*
Y-9231D01*
Y-9199D01*
Y-9166D01*
Y-9134D01*
Y-9102D01*
X460395D01*
Y-9069D01*
Y-9037D01*
Y-9005D01*
Y-8973D01*
Y-8940D01*
Y-8908D01*
Y-8876D01*
Y-8844D01*
Y-8811D01*
Y-8779D01*
X460427D01*
Y-8747D01*
Y-8715D01*
Y-8682D01*
Y-8650D01*
Y-8618D01*
X460459D01*
Y-8585D01*
Y-8553D01*
Y-8521D01*
X460492D01*
Y-8489D01*
Y-8456D01*
Y-8424D01*
X460524D01*
Y-8392D01*
Y-8360D01*
X460556D01*
Y-8327D01*
Y-8295D01*
X460588D01*
Y-8263D01*
X460620D01*
Y-8231D01*
Y-8198D01*
X460653D01*
Y-8166D01*
X460685D01*
Y-8134D01*
X460717D01*
Y-8102D01*
X460750D01*
Y-8069D01*
X460782D01*
Y-8037D01*
X460814D01*
Y-8005D01*
X460846D01*
Y-7972D01*
X460879D01*
Y-7940D01*
X460943D01*
Y-7908D01*
X461008D01*
Y-7876D01*
X461040D01*
Y-7843D01*
X461104D01*
Y-7811D01*
X461201D01*
Y-7779D01*
X461298D01*
Y-7747D01*
X461459D01*
Y-7714D01*
X461750D01*
Y-7747D01*
D02*
G37*
G36*
X461879Y-12134D02*
X462008D01*
Y-12167D01*
X462072D01*
Y-12199D01*
X462137D01*
Y-12231D01*
X462201D01*
Y-12263D01*
X462266D01*
Y-12296D01*
X462298D01*
Y-12328D01*
X462363D01*
Y-12360D01*
X462395D01*
Y-12392D01*
X462427D01*
Y-12425D01*
X462460D01*
Y-12457D01*
X462492D01*
Y-12489D01*
X462524D01*
Y-12521D01*
X462556D01*
Y-12554D01*
X462589D01*
Y-12586D01*
Y-12618D01*
X462621D01*
Y-12651D01*
X462653D01*
Y-12683D01*
Y-12715D01*
X462685D01*
Y-12747D01*
Y-12780D01*
X462718D01*
Y-12812D01*
Y-12844D01*
X462750D01*
Y-12876D01*
Y-12909D01*
Y-12941D01*
X462782D01*
Y-12973D01*
Y-13005D01*
Y-13038D01*
Y-13070D01*
Y-13102D01*
X462814D01*
Y-13134D01*
Y-13167D01*
Y-13199D01*
Y-13231D01*
Y-13263D01*
Y-13296D01*
Y-13328D01*
Y-13360D01*
Y-13393D01*
Y-13425D01*
Y-13457D01*
Y-13489D01*
X462782D01*
Y-13522D01*
Y-13554D01*
Y-13586D01*
Y-13618D01*
Y-13651D01*
X462750D01*
Y-13683D01*
Y-13715D01*
Y-13747D01*
X462718D01*
Y-13780D01*
Y-13812D01*
X462685D01*
Y-13844D01*
Y-13876D01*
X462653D01*
Y-13909D01*
Y-13941D01*
X462621D01*
Y-13973D01*
X462589D01*
Y-14006D01*
Y-14038D01*
X462556D01*
Y-14070D01*
X462524D01*
Y-14102D01*
X462492D01*
Y-14134D01*
X462460D01*
Y-14167D01*
X462427D01*
Y-14199D01*
X462395D01*
Y-14231D01*
X462363D01*
Y-14264D01*
X462298D01*
Y-14296D01*
X462266D01*
Y-14328D01*
X462201D01*
Y-14360D01*
X462137D01*
Y-14393D01*
X462072D01*
Y-14425D01*
X461976D01*
Y-14457D01*
X461879D01*
Y-14489D01*
X461330D01*
Y-14457D01*
X461234D01*
Y-14425D01*
X461137D01*
Y-14393D01*
X461072D01*
Y-14360D01*
X461008D01*
Y-14328D01*
X460943D01*
Y-14296D01*
X460911D01*
Y-14264D01*
X460879D01*
Y-14231D01*
X460814D01*
Y-14199D01*
X460782D01*
Y-14167D01*
X460750D01*
Y-14134D01*
X460717D01*
Y-14102D01*
X460685D01*
Y-14070D01*
X460653D01*
Y-14038D01*
Y-14006D01*
X460620D01*
Y-13973D01*
X460588D01*
Y-13941D01*
Y-13909D01*
X460556D01*
Y-13876D01*
Y-13844D01*
X460524D01*
Y-13812D01*
Y-13780D01*
X460492D01*
Y-13747D01*
Y-13715D01*
X460459D01*
Y-13683D01*
Y-13651D01*
Y-13618D01*
X460427D01*
Y-13586D01*
Y-13554D01*
Y-13522D01*
Y-13489D01*
Y-13457D01*
X460395D01*
Y-13425D01*
Y-13393D01*
Y-13360D01*
Y-13328D01*
Y-13296D01*
Y-13263D01*
Y-13231D01*
Y-13199D01*
Y-13167D01*
Y-13134D01*
X460427D01*
Y-13102D01*
Y-13070D01*
Y-13038D01*
Y-13005D01*
Y-12973D01*
X460459D01*
Y-12941D01*
Y-12909D01*
Y-12876D01*
X460492D01*
Y-12844D01*
Y-12812D01*
X460524D01*
Y-12780D01*
Y-12747D01*
X460556D01*
Y-12715D01*
Y-12683D01*
X460588D01*
Y-12651D01*
Y-12618D01*
X460620D01*
Y-12586D01*
X460653D01*
Y-12554D01*
Y-12521D01*
X460685D01*
Y-12489D01*
X460717D01*
Y-12457D01*
X460750D01*
Y-12425D01*
X460782D01*
Y-12392D01*
X460814D01*
Y-12360D01*
X460846D01*
Y-12328D01*
X460911D01*
Y-12296D01*
X460943D01*
Y-12263D01*
X461008D01*
Y-12231D01*
X461072D01*
Y-12199D01*
X461137D01*
Y-12167D01*
X461234D01*
Y-12134D01*
X461330D01*
Y-12102D01*
X461879D01*
Y-12134D01*
D02*
G37*
G36*
X457168Y14449D02*
X457491D01*
Y14417D01*
X457620D01*
Y14385D01*
X457749D01*
Y14353D01*
X457814D01*
Y14320D01*
X457911D01*
Y14288D01*
X457975D01*
Y14256D01*
X458040D01*
Y14224D01*
X458104D01*
Y14191D01*
X458169D01*
Y14159D01*
X458201D01*
Y14127D01*
X458265D01*
Y14095D01*
X458298D01*
Y14062D01*
X458330D01*
Y14030D01*
X458394D01*
Y13998D01*
X458427D01*
Y13965D01*
X458459D01*
Y13933D01*
X458491D01*
Y13901D01*
X458524D01*
Y13869D01*
X458556D01*
Y13836D01*
X458588D01*
Y13804D01*
X458620D01*
Y13772D01*
X458653D01*
Y13740D01*
Y13707D01*
X458685D01*
Y13675D01*
X458717D01*
Y13643D01*
X458749D01*
Y13611D01*
Y13578D01*
X458782D01*
Y13546D01*
X458814D01*
Y13514D01*
Y13482D01*
X458846D01*
Y13449D01*
Y13417D01*
X458878D01*
Y13385D01*
Y13352D01*
X458911D01*
Y13320D01*
Y13288D01*
X458943D01*
Y13256D01*
Y13223D01*
Y13191D01*
X458975D01*
Y13159D01*
Y13127D01*
X459008D01*
Y13094D01*
Y13062D01*
Y13030D01*
Y12998D01*
X459040D01*
Y12965D01*
Y12933D01*
Y12901D01*
Y12869D01*
Y12836D01*
X459072D01*
Y12804D01*
Y12772D01*
Y12740D01*
Y12707D01*
Y12675D01*
Y12643D01*
Y12610D01*
Y12578D01*
Y12546D01*
Y12514D01*
Y12481D01*
Y12449D01*
Y12417D01*
Y12385D01*
Y12352D01*
Y12320D01*
Y12288D01*
Y12256D01*
Y12223D01*
Y12191D01*
Y12159D01*
Y12127D01*
Y12094D01*
Y12062D01*
Y12030D01*
Y11998D01*
Y11965D01*
Y11933D01*
Y11901D01*
Y11868D01*
Y11836D01*
Y11804D01*
Y11772D01*
Y11739D01*
Y11707D01*
Y11675D01*
Y11643D01*
Y11610D01*
Y11578D01*
Y11546D01*
Y11514D01*
Y11481D01*
Y11449D01*
Y11417D01*
Y11384D01*
Y11352D01*
Y11320D01*
Y11288D01*
Y11255D01*
Y11223D01*
Y11191D01*
Y11159D01*
Y11126D01*
Y11094D01*
Y11062D01*
Y11030D01*
Y10997D01*
Y10965D01*
Y10933D01*
Y10901D01*
Y10868D01*
Y10836D01*
Y10804D01*
Y10772D01*
Y10739D01*
Y10707D01*
Y10675D01*
Y10643D01*
Y10610D01*
Y10578D01*
Y10546D01*
Y10514D01*
Y10481D01*
Y10449D01*
Y10417D01*
Y10384D01*
Y10352D01*
Y10320D01*
Y10288D01*
Y10255D01*
Y10223D01*
Y10191D01*
Y10159D01*
Y10126D01*
Y10094D01*
Y10062D01*
Y10029D01*
Y9997D01*
Y9965D01*
Y9933D01*
Y9900D01*
Y9868D01*
Y9836D01*
Y9804D01*
Y9771D01*
Y9739D01*
Y9707D01*
Y9675D01*
Y9642D01*
Y9610D01*
Y9578D01*
Y9546D01*
Y9513D01*
Y9481D01*
Y9449D01*
Y9417D01*
Y9384D01*
Y9352D01*
Y9320D01*
Y9287D01*
Y9255D01*
Y9223D01*
Y9191D01*
Y9159D01*
Y9126D01*
Y9094D01*
Y9062D01*
Y9029D01*
Y8997D01*
Y8965D01*
Y8933D01*
Y8900D01*
Y8868D01*
Y8836D01*
Y8804D01*
Y8771D01*
Y8739D01*
Y8707D01*
Y8675D01*
Y8642D01*
Y8610D01*
Y8578D01*
Y8546D01*
Y8513D01*
Y8481D01*
Y8449D01*
Y8416D01*
Y8384D01*
Y8352D01*
Y8320D01*
Y8287D01*
Y8255D01*
Y8223D01*
Y8191D01*
Y8158D01*
Y8126D01*
Y8094D01*
Y8062D01*
Y8029D01*
Y7997D01*
Y7965D01*
Y7932D01*
Y7900D01*
Y7868D01*
Y7836D01*
Y7803D01*
Y7771D01*
Y7739D01*
Y7707D01*
Y7674D01*
Y7642D01*
Y7610D01*
Y7578D01*
Y7545D01*
Y7513D01*
Y7481D01*
Y7449D01*
Y7416D01*
Y7384D01*
Y7352D01*
Y7320D01*
Y7287D01*
Y7255D01*
Y7223D01*
Y7191D01*
Y7158D01*
Y7126D01*
Y7094D01*
Y7062D01*
Y7029D01*
Y6997D01*
Y6965D01*
Y6932D01*
Y6900D01*
Y6868D01*
Y6836D01*
Y6803D01*
Y6771D01*
Y6739D01*
Y6707D01*
Y6674D01*
Y6642D01*
Y6610D01*
Y6577D01*
Y6545D01*
Y6513D01*
Y6481D01*
Y6448D01*
Y6416D01*
Y6384D01*
Y6352D01*
Y6319D01*
Y6287D01*
Y6255D01*
Y6223D01*
Y6190D01*
Y6158D01*
Y6126D01*
Y6094D01*
Y6061D01*
Y6029D01*
Y5997D01*
Y5965D01*
Y5932D01*
Y5900D01*
Y5868D01*
Y5835D01*
Y5803D01*
Y5771D01*
Y5739D01*
Y5706D01*
Y5674D01*
Y5642D01*
Y5610D01*
Y5577D01*
Y5545D01*
Y5513D01*
Y5481D01*
Y5448D01*
Y5416D01*
Y5384D01*
Y5352D01*
Y5319D01*
Y5287D01*
Y5255D01*
Y5223D01*
Y5190D01*
Y5158D01*
Y5126D01*
Y5094D01*
Y5061D01*
Y5029D01*
Y4997D01*
Y4964D01*
Y4932D01*
Y4900D01*
Y4868D01*
Y4835D01*
Y4803D01*
Y4771D01*
Y4739D01*
Y4706D01*
Y4674D01*
Y4642D01*
Y4610D01*
Y4577D01*
Y4545D01*
Y4513D01*
Y4481D01*
Y4448D01*
Y4416D01*
Y4384D01*
Y4352D01*
Y4319D01*
Y4287D01*
Y4255D01*
Y4222D01*
Y4190D01*
Y4158D01*
Y4126D01*
Y4093D01*
Y4061D01*
Y4029D01*
Y3997D01*
Y3964D01*
Y3932D01*
Y3900D01*
Y3867D01*
Y3835D01*
Y3803D01*
Y3771D01*
Y3739D01*
Y3706D01*
Y3674D01*
Y3642D01*
Y3609D01*
Y3577D01*
Y3545D01*
Y3513D01*
Y3480D01*
Y3448D01*
Y3416D01*
Y3384D01*
Y3351D01*
Y3319D01*
Y3287D01*
Y3255D01*
Y3222D01*
Y3190D01*
Y3158D01*
Y3125D01*
Y3093D01*
Y3061D01*
Y3029D01*
Y2997D01*
Y2964D01*
Y2932D01*
Y2900D01*
Y2867D01*
Y2835D01*
Y2803D01*
Y2771D01*
Y2738D01*
Y2706D01*
Y2674D01*
Y2642D01*
Y2609D01*
Y2577D01*
Y2545D01*
Y2513D01*
Y2480D01*
Y2448D01*
Y2416D01*
Y2383D01*
Y2351D01*
Y2319D01*
Y2287D01*
Y2254D01*
Y2222D01*
Y2190D01*
Y2158D01*
Y2125D01*
Y2093D01*
Y2061D01*
Y2029D01*
Y1996D01*
Y1964D01*
Y1932D01*
Y1900D01*
Y1867D01*
Y1835D01*
Y1803D01*
Y1770D01*
Y1738D01*
Y1706D01*
Y1674D01*
Y1641D01*
Y1609D01*
Y1577D01*
Y1545D01*
Y1512D01*
Y1480D01*
Y1448D01*
Y1416D01*
Y1383D01*
Y1351D01*
Y1319D01*
Y1287D01*
Y1254D01*
Y1222D01*
Y1190D01*
Y1158D01*
Y1125D01*
Y1093D01*
Y1061D01*
Y1029D01*
Y996D01*
Y964D01*
Y932D01*
Y900D01*
Y867D01*
Y835D01*
Y803D01*
Y770D01*
Y738D01*
Y706D01*
Y674D01*
Y641D01*
Y609D01*
Y577D01*
Y545D01*
Y512D01*
Y480D01*
Y448D01*
Y416D01*
Y383D01*
Y351D01*
Y319D01*
Y286D01*
Y254D01*
Y222D01*
Y190D01*
Y157D01*
Y125D01*
Y93D01*
Y61D01*
Y28D01*
Y-4D01*
Y-36D01*
Y-68D01*
Y-101D01*
Y-133D01*
Y-165D01*
Y-197D01*
Y-230D01*
Y-262D01*
Y-294D01*
Y-326D01*
Y-359D01*
Y-391D01*
Y-423D01*
Y-455D01*
Y-488D01*
Y-520D01*
Y-552D01*
Y-585D01*
Y-617D01*
Y-649D01*
Y-681D01*
Y-714D01*
Y-746D01*
Y-778D01*
Y-810D01*
Y-843D01*
Y-875D01*
Y-907D01*
Y-939D01*
Y-972D01*
Y-1004D01*
Y-1036D01*
Y-1068D01*
Y-1101D01*
Y-1133D01*
Y-1165D01*
Y-1198D01*
Y-1230D01*
Y-1262D01*
Y-1294D01*
Y-1327D01*
Y-1359D01*
Y-1391D01*
Y-1423D01*
Y-1456D01*
Y-1488D01*
Y-1520D01*
Y-1552D01*
Y-1585D01*
Y-1617D01*
Y-1649D01*
Y-1681D01*
Y-1714D01*
Y-1746D01*
Y-1778D01*
Y-1811D01*
Y-1843D01*
Y-1875D01*
Y-1907D01*
Y-1940D01*
Y-1972D01*
Y-2004D01*
Y-2036D01*
Y-2069D01*
Y-2101D01*
Y-2133D01*
Y-2165D01*
Y-2198D01*
Y-2230D01*
Y-2262D01*
Y-2294D01*
Y-2327D01*
Y-2359D01*
Y-2391D01*
Y-2424D01*
Y-2456D01*
Y-2488D01*
Y-2520D01*
Y-2553D01*
Y-2585D01*
Y-2617D01*
Y-2649D01*
Y-2682D01*
Y-2714D01*
Y-2746D01*
Y-2778D01*
Y-2811D01*
Y-2843D01*
Y-2875D01*
Y-2907D01*
Y-2940D01*
Y-2972D01*
Y-3004D01*
Y-3036D01*
Y-3069D01*
Y-3101D01*
Y-3133D01*
Y-3165D01*
Y-3198D01*
Y-3230D01*
Y-3262D01*
Y-3295D01*
Y-3327D01*
Y-3359D01*
Y-3391D01*
Y-3424D01*
Y-3456D01*
Y-3488D01*
Y-3520D01*
Y-3553D01*
Y-3585D01*
Y-3617D01*
Y-3650D01*
Y-3682D01*
Y-3714D01*
Y-3746D01*
Y-3779D01*
Y-3811D01*
Y-3843D01*
Y-3875D01*
Y-3907D01*
Y-3940D01*
Y-3972D01*
Y-4004D01*
Y-4037D01*
Y-4069D01*
Y-4101D01*
Y-4133D01*
Y-4166D01*
Y-4198D01*
Y-4230D01*
Y-4262D01*
Y-4295D01*
Y-4327D01*
Y-4359D01*
Y-4391D01*
Y-4424D01*
Y-4456D01*
Y-4488D01*
Y-4521D01*
Y-4553D01*
Y-4585D01*
Y-4617D01*
Y-4650D01*
Y-4682D01*
Y-4714D01*
Y-4746D01*
Y-4779D01*
Y-4811D01*
Y-4843D01*
Y-4875D01*
Y-4908D01*
Y-4940D01*
Y-4972D01*
Y-5004D01*
Y-5037D01*
Y-5069D01*
Y-5101D01*
Y-5133D01*
Y-5166D01*
Y-5198D01*
Y-5230D01*
Y-5263D01*
Y-5295D01*
Y-5327D01*
Y-5359D01*
Y-5392D01*
Y-5424D01*
Y-5456D01*
Y-5488D01*
Y-5521D01*
Y-5553D01*
Y-5585D01*
Y-5617D01*
Y-5650D01*
Y-5682D01*
Y-5714D01*
Y-5746D01*
Y-5779D01*
Y-5811D01*
Y-5843D01*
Y-5875D01*
Y-5908D01*
Y-5940D01*
Y-5972D01*
Y-6005D01*
Y-6037D01*
Y-6069D01*
Y-6101D01*
Y-6134D01*
Y-6166D01*
Y-6198D01*
Y-6230D01*
Y-6263D01*
Y-6295D01*
Y-6327D01*
Y-6359D01*
Y-6392D01*
Y-6424D01*
Y-6456D01*
Y-6488D01*
Y-6521D01*
Y-6553D01*
Y-6585D01*
Y-6617D01*
Y-6650D01*
Y-6682D01*
Y-6714D01*
Y-6747D01*
Y-6779D01*
Y-6811D01*
Y-6843D01*
Y-6876D01*
Y-6908D01*
Y-6940D01*
Y-6972D01*
Y-7005D01*
Y-7037D01*
Y-7069D01*
Y-7102D01*
Y-7134D01*
Y-7166D01*
Y-7198D01*
Y-7231D01*
Y-7263D01*
Y-7295D01*
Y-7327D01*
Y-7360D01*
Y-7392D01*
Y-7424D01*
Y-7456D01*
Y-7489D01*
Y-7521D01*
Y-7553D01*
Y-7585D01*
Y-7618D01*
Y-7650D01*
Y-7682D01*
Y-7714D01*
Y-7747D01*
Y-7779D01*
Y-7811D01*
Y-7843D01*
Y-7876D01*
Y-7908D01*
Y-7940D01*
Y-7972D01*
Y-8005D01*
Y-8037D01*
Y-8069D01*
Y-8102D01*
Y-8134D01*
Y-8166D01*
Y-8198D01*
Y-8231D01*
Y-8263D01*
Y-8295D01*
Y-8327D01*
Y-8360D01*
Y-8392D01*
Y-8424D01*
Y-8456D01*
Y-8489D01*
Y-8521D01*
Y-8553D01*
Y-8585D01*
Y-8618D01*
Y-8650D01*
Y-8682D01*
Y-8715D01*
Y-8747D01*
Y-8779D01*
Y-8811D01*
Y-8844D01*
Y-8876D01*
Y-8908D01*
Y-8940D01*
Y-8973D01*
Y-9005D01*
Y-9037D01*
Y-9069D01*
Y-9102D01*
Y-9134D01*
Y-9166D01*
Y-9199D01*
Y-9231D01*
Y-9263D01*
Y-9295D01*
Y-9328D01*
Y-9360D01*
Y-9392D01*
Y-9424D01*
Y-9457D01*
Y-9489D01*
Y-9521D01*
Y-9553D01*
Y-9586D01*
Y-9618D01*
Y-9650D01*
Y-9682D01*
Y-9715D01*
Y-9747D01*
Y-9779D01*
Y-9811D01*
Y-9844D01*
Y-9876D01*
Y-9908D01*
Y-9940D01*
Y-9973D01*
Y-10005D01*
Y-10037D01*
Y-10069D01*
Y-10102D01*
Y-10134D01*
Y-10166D01*
Y-10199D01*
Y-10231D01*
Y-10263D01*
Y-10295D01*
Y-10328D01*
Y-10360D01*
Y-10392D01*
Y-10424D01*
Y-10457D01*
Y-10489D01*
Y-10521D01*
Y-10554D01*
Y-10586D01*
Y-10618D01*
Y-10650D01*
Y-10683D01*
Y-10715D01*
Y-10747D01*
Y-10779D01*
Y-10812D01*
Y-10844D01*
Y-10876D01*
Y-10908D01*
Y-10941D01*
Y-10973D01*
Y-11005D01*
Y-11037D01*
Y-11070D01*
Y-11102D01*
Y-11134D01*
Y-11167D01*
Y-11199D01*
Y-11231D01*
Y-11263D01*
Y-11295D01*
Y-11328D01*
Y-11360D01*
Y-11392D01*
Y-11425D01*
Y-11457D01*
Y-11489D01*
Y-11521D01*
Y-11554D01*
Y-11586D01*
Y-11618D01*
Y-11650D01*
Y-11683D01*
Y-11715D01*
Y-11747D01*
Y-11779D01*
Y-11812D01*
Y-11844D01*
Y-11876D01*
Y-11908D01*
Y-11941D01*
Y-11973D01*
Y-12005D01*
Y-12037D01*
Y-12070D01*
Y-12102D01*
Y-12134D01*
Y-12167D01*
Y-12199D01*
Y-12231D01*
Y-12263D01*
Y-12296D01*
Y-12328D01*
Y-12360D01*
Y-12392D01*
Y-12425D01*
Y-12457D01*
Y-12489D01*
Y-12521D01*
Y-12554D01*
Y-12586D01*
Y-12618D01*
Y-12651D01*
Y-12683D01*
Y-12715D01*
Y-12747D01*
Y-12780D01*
Y-12812D01*
Y-12844D01*
Y-12876D01*
Y-12909D01*
Y-12941D01*
Y-12973D01*
Y-13005D01*
Y-13038D01*
Y-13070D01*
Y-13102D01*
Y-13134D01*
Y-13167D01*
Y-13199D01*
Y-13231D01*
Y-13263D01*
Y-13296D01*
Y-13328D01*
Y-13360D01*
Y-13393D01*
Y-13425D01*
Y-13457D01*
Y-13489D01*
Y-13522D01*
Y-13554D01*
Y-13586D01*
Y-13618D01*
Y-13651D01*
Y-13683D01*
Y-13715D01*
Y-13747D01*
Y-13780D01*
Y-13812D01*
Y-13844D01*
Y-13876D01*
Y-13909D01*
Y-13941D01*
Y-13973D01*
Y-14006D01*
Y-14038D01*
Y-14070D01*
Y-14102D01*
Y-14134D01*
Y-14167D01*
Y-14199D01*
Y-14231D01*
Y-14264D01*
Y-14296D01*
Y-14328D01*
Y-14360D01*
Y-14393D01*
Y-14425D01*
Y-14457D01*
Y-14489D01*
Y-14522D01*
Y-14554D01*
Y-14586D01*
Y-14618D01*
Y-14651D01*
Y-14683D01*
Y-14715D01*
Y-14748D01*
Y-14780D01*
Y-14812D01*
Y-14844D01*
Y-14877D01*
Y-14909D01*
Y-14941D01*
Y-14973D01*
Y-15006D01*
Y-15038D01*
Y-15070D01*
Y-15102D01*
Y-15135D01*
Y-15167D01*
Y-15199D01*
Y-15231D01*
Y-15264D01*
Y-15296D01*
Y-15328D01*
Y-15360D01*
Y-15393D01*
Y-15425D01*
Y-15457D01*
Y-15489D01*
Y-15522D01*
Y-15554D01*
Y-15586D01*
Y-15619D01*
Y-15651D01*
Y-15683D01*
Y-15715D01*
Y-15748D01*
Y-15780D01*
Y-15812D01*
Y-15844D01*
Y-15877D01*
Y-15909D01*
Y-15941D01*
Y-15973D01*
Y-16006D01*
Y-16038D01*
Y-16070D01*
Y-16103D01*
Y-16135D01*
Y-16167D01*
Y-16199D01*
Y-16232D01*
Y-16264D01*
Y-16296D01*
Y-16328D01*
Y-16361D01*
Y-16393D01*
Y-16425D01*
Y-16457D01*
Y-16490D01*
Y-16522D01*
Y-16554D01*
Y-16586D01*
Y-16619D01*
Y-16651D01*
Y-16683D01*
Y-16715D01*
Y-16748D01*
Y-16780D01*
Y-16812D01*
Y-16845D01*
Y-16877D01*
Y-16909D01*
Y-16941D01*
Y-16974D01*
Y-17006D01*
Y-17038D01*
Y-17070D01*
Y-17103D01*
Y-17135D01*
Y-17167D01*
Y-17199D01*
Y-17232D01*
Y-17264D01*
Y-17296D01*
Y-17328D01*
Y-17361D01*
Y-17393D01*
Y-17425D01*
Y-17458D01*
Y-17490D01*
Y-17522D01*
Y-17554D01*
Y-17586D01*
Y-17619D01*
Y-17651D01*
Y-17683D01*
Y-17716D01*
Y-17748D01*
Y-17780D01*
Y-17812D01*
Y-17845D01*
Y-17877D01*
Y-17909D01*
Y-17941D01*
Y-17974D01*
Y-18006D01*
Y-18038D01*
Y-18070D01*
Y-18103D01*
Y-18135D01*
Y-18167D01*
Y-18200D01*
Y-18232D01*
Y-18264D01*
Y-18296D01*
Y-18329D01*
Y-18361D01*
Y-18393D01*
Y-18425D01*
Y-18458D01*
Y-18490D01*
Y-18522D01*
Y-18554D01*
Y-18587D01*
Y-18619D01*
Y-18651D01*
Y-18683D01*
Y-18716D01*
Y-18748D01*
Y-18780D01*
Y-18812D01*
Y-18845D01*
Y-18877D01*
Y-18909D01*
Y-18941D01*
Y-18974D01*
Y-19006D01*
Y-19038D01*
Y-19071D01*
Y-19103D01*
Y-19135D01*
Y-19167D01*
Y-19200D01*
Y-19232D01*
Y-19264D01*
Y-19296D01*
Y-19329D01*
Y-19361D01*
Y-19393D01*
Y-19425D01*
Y-19458D01*
Y-19490D01*
Y-19522D01*
Y-19555D01*
Y-19587D01*
Y-19619D01*
Y-19651D01*
Y-19684D01*
Y-19716D01*
Y-19748D01*
Y-19780D01*
Y-19813D01*
Y-19845D01*
Y-19877D01*
Y-19909D01*
Y-19942D01*
Y-19974D01*
Y-20006D01*
Y-20039D01*
Y-20071D01*
Y-20103D01*
Y-20135D01*
Y-20167D01*
Y-20200D01*
Y-20232D01*
Y-20264D01*
Y-20297D01*
Y-20329D01*
Y-20361D01*
Y-20393D01*
Y-20426D01*
Y-20458D01*
Y-20490D01*
Y-20522D01*
Y-20555D01*
Y-20587D01*
Y-20619D01*
Y-20651D01*
Y-20684D01*
Y-20716D01*
Y-20748D01*
Y-20780D01*
Y-20813D01*
Y-20845D01*
Y-20877D01*
Y-20910D01*
Y-20942D01*
Y-20974D01*
Y-21006D01*
Y-21039D01*
Y-21071D01*
Y-21103D01*
Y-21135D01*
Y-21168D01*
Y-21200D01*
Y-21232D01*
Y-21264D01*
Y-21297D01*
Y-21329D01*
Y-21361D01*
Y-21393D01*
Y-21426D01*
Y-21458D01*
Y-21490D01*
Y-21522D01*
Y-21555D01*
Y-21587D01*
Y-21619D01*
Y-21652D01*
Y-21684D01*
Y-21716D01*
Y-21748D01*
Y-21781D01*
Y-21813D01*
Y-21845D01*
Y-21877D01*
Y-21910D01*
Y-21942D01*
Y-21974D01*
Y-22006D01*
Y-22039D01*
Y-22071D01*
Y-22103D01*
Y-22136D01*
Y-22168D01*
Y-22200D01*
Y-22232D01*
Y-22264D01*
Y-22297D01*
Y-22329D01*
Y-22361D01*
Y-22394D01*
X457878D01*
Y-22361D01*
Y-22329D01*
Y-22297D01*
Y-22264D01*
Y-22232D01*
Y-22200D01*
Y-22168D01*
Y-22136D01*
Y-22103D01*
Y-22071D01*
Y-22039D01*
Y-22006D01*
Y-21974D01*
Y-21942D01*
Y-21910D01*
Y-21877D01*
Y-21845D01*
Y-21813D01*
Y-21781D01*
Y-21748D01*
Y-21716D01*
Y-21684D01*
Y-21652D01*
Y-21619D01*
Y-21587D01*
Y-21555D01*
Y-21522D01*
Y-21490D01*
Y-21458D01*
Y-21426D01*
Y-21393D01*
Y-21361D01*
Y-21329D01*
Y-21297D01*
Y-21264D01*
Y-21232D01*
Y-21200D01*
Y-21168D01*
Y-21135D01*
Y-21103D01*
Y-21071D01*
Y-21039D01*
Y-21006D01*
Y-20974D01*
Y-20942D01*
Y-20910D01*
Y-20877D01*
Y-20845D01*
Y-20813D01*
Y-20780D01*
Y-20748D01*
Y-20716D01*
Y-20684D01*
Y-20651D01*
Y-20619D01*
Y-20587D01*
Y-20555D01*
Y-20522D01*
Y-20490D01*
Y-20458D01*
Y-20426D01*
Y-20393D01*
Y-20361D01*
Y-20329D01*
Y-20297D01*
Y-20264D01*
Y-20232D01*
Y-20200D01*
Y-20167D01*
Y-20135D01*
Y-20103D01*
Y-20071D01*
Y-20039D01*
Y-20006D01*
Y-19974D01*
Y-19942D01*
Y-19909D01*
Y-19877D01*
Y-19845D01*
Y-19813D01*
Y-19780D01*
Y-19748D01*
Y-19716D01*
Y-19684D01*
Y-19651D01*
Y-19619D01*
Y-19587D01*
Y-19555D01*
Y-19522D01*
Y-19490D01*
Y-19458D01*
Y-19425D01*
Y-19393D01*
Y-19361D01*
Y-19329D01*
Y-19296D01*
Y-19264D01*
Y-19232D01*
Y-19200D01*
Y-19167D01*
Y-19135D01*
Y-19103D01*
Y-19071D01*
Y-19038D01*
Y-19006D01*
Y-18974D01*
Y-18941D01*
Y-18909D01*
Y-18877D01*
Y-18845D01*
Y-18812D01*
Y-18780D01*
Y-18748D01*
Y-18716D01*
Y-18683D01*
Y-18651D01*
Y-18619D01*
Y-18587D01*
Y-18554D01*
Y-18522D01*
Y-18490D01*
Y-18458D01*
Y-18425D01*
Y-18393D01*
Y-18361D01*
Y-18329D01*
Y-18296D01*
Y-18264D01*
Y-18232D01*
Y-18200D01*
Y-18167D01*
Y-18135D01*
Y-18103D01*
Y-18070D01*
Y-18038D01*
Y-18006D01*
Y-17974D01*
Y-17941D01*
Y-17909D01*
Y-17877D01*
Y-17845D01*
Y-17812D01*
Y-17780D01*
Y-17748D01*
Y-17716D01*
Y-17683D01*
Y-17651D01*
Y-17619D01*
Y-17586D01*
Y-17554D01*
Y-17522D01*
Y-17490D01*
Y-17458D01*
Y-17425D01*
Y-17393D01*
Y-17361D01*
Y-17328D01*
Y-17296D01*
Y-17264D01*
Y-17232D01*
Y-17199D01*
Y-17167D01*
Y-17135D01*
Y-17103D01*
Y-17070D01*
Y-17038D01*
Y-17006D01*
Y-16974D01*
Y-16941D01*
Y-16909D01*
Y-16877D01*
Y-16845D01*
Y-16812D01*
Y-16780D01*
Y-16748D01*
Y-16715D01*
Y-16683D01*
Y-16651D01*
Y-16619D01*
Y-16586D01*
Y-16554D01*
Y-16522D01*
Y-16490D01*
Y-16457D01*
Y-16425D01*
Y-16393D01*
Y-16361D01*
Y-16328D01*
Y-16296D01*
Y-16264D01*
Y-16232D01*
Y-16199D01*
Y-16167D01*
Y-16135D01*
Y-16103D01*
Y-16070D01*
Y-16038D01*
Y-16006D01*
Y-15973D01*
Y-15941D01*
Y-15909D01*
Y-15877D01*
Y-15844D01*
Y-15812D01*
Y-15780D01*
Y-15748D01*
Y-15715D01*
Y-15683D01*
Y-15651D01*
Y-15619D01*
Y-15586D01*
Y-15554D01*
Y-15522D01*
Y-15489D01*
Y-15457D01*
Y-15425D01*
Y-15393D01*
Y-15360D01*
Y-15328D01*
Y-15296D01*
Y-15264D01*
Y-15231D01*
Y-15199D01*
Y-15167D01*
Y-15135D01*
Y-15102D01*
Y-15070D01*
Y-15038D01*
Y-15006D01*
Y-14973D01*
Y-14941D01*
Y-14909D01*
Y-14877D01*
Y-14844D01*
Y-14812D01*
Y-14780D01*
Y-14748D01*
Y-14715D01*
Y-14683D01*
Y-14651D01*
Y-14618D01*
Y-14586D01*
Y-14554D01*
Y-14522D01*
Y-14489D01*
Y-14457D01*
Y-14425D01*
Y-14393D01*
Y-14360D01*
Y-14328D01*
Y-14296D01*
Y-14264D01*
Y-14231D01*
Y-14199D01*
Y-14167D01*
Y-14134D01*
Y-14102D01*
Y-14070D01*
Y-14038D01*
Y-14006D01*
Y-13973D01*
Y-13941D01*
Y-13909D01*
Y-13876D01*
Y-13844D01*
Y-13812D01*
Y-13780D01*
Y-13747D01*
Y-13715D01*
Y-13683D01*
Y-13651D01*
Y-13618D01*
Y-13586D01*
Y-13554D01*
Y-13522D01*
Y-13489D01*
Y-13457D01*
Y-13425D01*
Y-13393D01*
Y-13360D01*
Y-13328D01*
Y-13296D01*
Y-13263D01*
Y-13231D01*
Y-13199D01*
Y-13167D01*
Y-13134D01*
Y-13102D01*
Y-13070D01*
Y-13038D01*
Y-13005D01*
Y-12973D01*
Y-12941D01*
Y-12909D01*
Y-12876D01*
Y-12844D01*
Y-12812D01*
Y-12780D01*
Y-12747D01*
Y-12715D01*
Y-12683D01*
Y-12651D01*
Y-12618D01*
Y-12586D01*
Y-12554D01*
Y-12521D01*
Y-12489D01*
Y-12457D01*
Y-12425D01*
Y-12392D01*
Y-12360D01*
Y-12328D01*
Y-12296D01*
Y-12263D01*
Y-12231D01*
Y-12199D01*
Y-12167D01*
Y-12134D01*
Y-12102D01*
Y-12070D01*
Y-12037D01*
Y-12005D01*
Y-11973D01*
Y-11941D01*
Y-11908D01*
Y-11876D01*
Y-11844D01*
Y-11812D01*
Y-11779D01*
Y-11747D01*
Y-11715D01*
Y-11683D01*
Y-11650D01*
Y-11618D01*
Y-11586D01*
Y-11554D01*
Y-11521D01*
Y-11489D01*
Y-11457D01*
Y-11425D01*
Y-11392D01*
Y-11360D01*
Y-11328D01*
Y-11295D01*
Y-11263D01*
Y-11231D01*
Y-11199D01*
Y-11167D01*
Y-11134D01*
Y-11102D01*
Y-11070D01*
Y-11037D01*
Y-11005D01*
Y-10973D01*
Y-10941D01*
Y-10908D01*
Y-10876D01*
Y-10844D01*
Y-10812D01*
Y-10779D01*
Y-10747D01*
Y-10715D01*
Y-10683D01*
Y-10650D01*
Y-10618D01*
Y-10586D01*
Y-10554D01*
Y-10521D01*
Y-10489D01*
Y-10457D01*
Y-10424D01*
Y-10392D01*
Y-10360D01*
Y-10328D01*
Y-10295D01*
Y-10263D01*
Y-10231D01*
Y-10199D01*
Y-10166D01*
Y-10134D01*
Y-10102D01*
Y-10069D01*
Y-10037D01*
Y-10005D01*
Y-9973D01*
Y-9940D01*
Y-9908D01*
Y-9876D01*
Y-9844D01*
Y-9811D01*
Y-9779D01*
Y-9747D01*
Y-9715D01*
Y-9682D01*
Y-9650D01*
Y-9618D01*
Y-9586D01*
Y-9553D01*
Y-9521D01*
Y-9489D01*
Y-9457D01*
Y-9424D01*
Y-9392D01*
Y-9360D01*
Y-9328D01*
Y-9295D01*
Y-9263D01*
Y-9231D01*
Y-9199D01*
Y-9166D01*
Y-9134D01*
Y-9102D01*
Y-9069D01*
Y-9037D01*
Y-9005D01*
Y-8973D01*
Y-8940D01*
Y-8908D01*
Y-8876D01*
Y-8844D01*
Y-8811D01*
Y-8779D01*
Y-8747D01*
Y-8715D01*
Y-8682D01*
Y-8650D01*
Y-8618D01*
Y-8585D01*
Y-8553D01*
Y-8521D01*
Y-8489D01*
Y-8456D01*
Y-8424D01*
Y-8392D01*
Y-8360D01*
Y-8327D01*
Y-8295D01*
Y-8263D01*
Y-8231D01*
Y-8198D01*
Y-8166D01*
Y-8134D01*
Y-8102D01*
Y-8069D01*
Y-8037D01*
Y-8005D01*
Y-7972D01*
Y-7940D01*
Y-7908D01*
Y-7876D01*
Y-7843D01*
Y-7811D01*
Y-7779D01*
Y-7747D01*
Y-7714D01*
Y-7682D01*
Y-7650D01*
Y-7618D01*
Y-7585D01*
Y-7553D01*
Y-7521D01*
Y-7489D01*
Y-7456D01*
Y-7424D01*
Y-7392D01*
Y-7360D01*
Y-7327D01*
Y-7295D01*
Y-7263D01*
Y-7231D01*
Y-7198D01*
Y-7166D01*
Y-7134D01*
Y-7102D01*
Y-7069D01*
Y-7037D01*
Y-7005D01*
Y-6972D01*
Y-6940D01*
Y-6908D01*
Y-6876D01*
Y-6843D01*
Y-6811D01*
Y-6779D01*
Y-6747D01*
Y-6714D01*
Y-6682D01*
Y-6650D01*
Y-6617D01*
Y-6585D01*
Y-6553D01*
Y-6521D01*
Y-6488D01*
Y-6456D01*
Y-6424D01*
Y-6392D01*
Y-6359D01*
Y-6327D01*
Y-6295D01*
Y-6263D01*
Y-6230D01*
Y-6198D01*
Y-6166D01*
Y-6134D01*
Y-6101D01*
Y-6069D01*
Y-6037D01*
Y-6005D01*
Y-5972D01*
Y-5940D01*
Y-5908D01*
Y-5875D01*
Y-5843D01*
Y-5811D01*
Y-5779D01*
Y-5746D01*
Y-5714D01*
Y-5682D01*
Y-5650D01*
Y-5617D01*
Y-5585D01*
Y-5553D01*
Y-5521D01*
Y-5488D01*
Y-5456D01*
Y-5424D01*
Y-5392D01*
Y-5359D01*
Y-5327D01*
Y-5295D01*
Y-5263D01*
Y-5230D01*
Y-5198D01*
Y-5166D01*
Y-5133D01*
Y-5101D01*
Y-5069D01*
Y-5037D01*
Y-5004D01*
Y-4972D01*
Y-4940D01*
Y-4908D01*
Y-4875D01*
Y-4843D01*
Y-4811D01*
Y-4779D01*
Y-4746D01*
Y-4714D01*
Y-4682D01*
Y-4650D01*
Y-4617D01*
Y-4585D01*
Y-4553D01*
Y-4521D01*
Y-4488D01*
Y-4456D01*
Y-4424D01*
Y-4391D01*
Y-4359D01*
Y-4327D01*
Y-4295D01*
Y-4262D01*
Y-4230D01*
Y-4198D01*
Y-4166D01*
Y-4133D01*
Y-4101D01*
Y-4069D01*
Y-4037D01*
Y-4004D01*
Y-3972D01*
Y-3940D01*
Y-3907D01*
Y-3875D01*
Y-3843D01*
Y-3811D01*
Y-3779D01*
Y-3746D01*
Y-3714D01*
Y-3682D01*
Y-3650D01*
Y-3617D01*
Y-3585D01*
Y-3553D01*
Y-3520D01*
Y-3488D01*
Y-3456D01*
Y-3424D01*
Y-3391D01*
Y-3359D01*
Y-3327D01*
Y-3295D01*
Y-3262D01*
Y-3230D01*
Y-3198D01*
Y-3165D01*
Y-3133D01*
Y-3101D01*
Y-3069D01*
Y-3036D01*
Y-3004D01*
Y-2972D01*
Y-2940D01*
Y-2907D01*
Y-2875D01*
Y-2843D01*
Y-2811D01*
Y-2778D01*
Y-2746D01*
Y-2714D01*
Y-2682D01*
Y-2649D01*
Y-2617D01*
Y-2585D01*
Y-2553D01*
Y-2520D01*
Y-2488D01*
Y-2456D01*
Y-2424D01*
Y-2391D01*
Y-2359D01*
Y-2327D01*
Y-2294D01*
Y-2262D01*
Y-2230D01*
Y-2198D01*
Y-2165D01*
Y-2133D01*
Y-2101D01*
Y-2069D01*
Y-2036D01*
Y-2004D01*
Y-1972D01*
Y-1940D01*
Y-1907D01*
Y-1875D01*
Y-1843D01*
Y-1811D01*
Y-1778D01*
Y-1746D01*
Y-1714D01*
Y-1681D01*
Y-1649D01*
Y-1617D01*
Y-1585D01*
Y-1552D01*
Y-1520D01*
Y-1488D01*
Y-1456D01*
Y-1423D01*
Y-1391D01*
Y-1359D01*
Y-1327D01*
Y-1294D01*
Y-1262D01*
Y-1230D01*
Y-1198D01*
Y-1165D01*
Y-1133D01*
Y-1101D01*
Y-1068D01*
Y-1036D01*
Y-1004D01*
Y-972D01*
Y-939D01*
Y-907D01*
Y-875D01*
Y-843D01*
Y-810D01*
Y-778D01*
Y-746D01*
Y-714D01*
Y-681D01*
Y-649D01*
Y-617D01*
Y-585D01*
Y-552D01*
Y-520D01*
Y-488D01*
Y-455D01*
Y-423D01*
Y-391D01*
Y-359D01*
Y-326D01*
Y-294D01*
Y-262D01*
Y-230D01*
Y-197D01*
Y-165D01*
Y-133D01*
Y-101D01*
Y-68D01*
Y-36D01*
Y-4D01*
Y28D01*
Y61D01*
Y93D01*
Y125D01*
Y157D01*
Y190D01*
Y222D01*
Y254D01*
Y286D01*
Y319D01*
Y351D01*
Y383D01*
Y416D01*
Y448D01*
Y480D01*
Y512D01*
Y545D01*
Y577D01*
Y609D01*
Y641D01*
Y674D01*
Y706D01*
Y738D01*
Y770D01*
Y803D01*
Y835D01*
Y867D01*
Y900D01*
Y932D01*
Y964D01*
Y996D01*
Y1029D01*
Y1061D01*
Y1093D01*
Y1125D01*
Y1158D01*
Y1190D01*
Y1222D01*
Y1254D01*
Y1287D01*
Y1319D01*
Y1351D01*
Y1383D01*
Y1416D01*
Y1448D01*
Y1480D01*
Y1512D01*
Y1545D01*
Y1577D01*
Y1609D01*
Y1641D01*
Y1674D01*
Y1706D01*
Y1738D01*
Y1770D01*
Y1803D01*
Y1835D01*
Y1867D01*
Y1900D01*
Y1932D01*
Y1964D01*
Y1996D01*
Y2029D01*
Y2061D01*
Y2093D01*
Y2125D01*
Y2158D01*
Y2190D01*
Y2222D01*
Y2254D01*
Y2287D01*
Y2319D01*
Y2351D01*
Y2383D01*
Y2416D01*
Y2448D01*
Y2480D01*
Y2513D01*
Y2545D01*
Y2577D01*
Y2609D01*
Y2642D01*
Y2674D01*
Y2706D01*
Y2738D01*
Y2771D01*
Y2803D01*
Y2835D01*
Y2867D01*
Y2900D01*
Y2932D01*
Y2964D01*
Y2997D01*
Y3029D01*
Y3061D01*
Y3093D01*
Y3125D01*
Y3158D01*
Y3190D01*
Y3222D01*
Y3255D01*
Y3287D01*
Y3319D01*
Y3351D01*
Y3384D01*
Y3416D01*
Y3448D01*
Y3480D01*
Y3513D01*
Y3545D01*
Y3577D01*
Y3609D01*
Y3642D01*
Y3674D01*
Y3706D01*
Y3739D01*
Y3771D01*
Y3803D01*
Y3835D01*
Y3867D01*
Y3900D01*
Y3932D01*
Y3964D01*
Y3997D01*
Y4029D01*
Y4061D01*
Y4093D01*
Y4126D01*
Y4158D01*
Y4190D01*
Y4222D01*
Y4255D01*
Y4287D01*
Y4319D01*
Y4352D01*
Y4384D01*
Y4416D01*
Y4448D01*
Y4481D01*
Y4513D01*
Y4545D01*
Y4577D01*
Y4610D01*
Y4642D01*
Y4674D01*
Y4706D01*
Y4739D01*
Y4771D01*
Y4803D01*
Y4835D01*
Y4868D01*
Y4900D01*
Y4932D01*
Y4964D01*
Y4997D01*
Y5029D01*
Y5061D01*
Y5094D01*
Y5126D01*
Y5158D01*
Y5190D01*
Y5223D01*
Y5255D01*
Y5287D01*
Y5319D01*
Y5352D01*
Y5384D01*
Y5416D01*
Y5448D01*
Y5481D01*
Y5513D01*
Y5545D01*
Y5577D01*
Y5610D01*
Y5642D01*
Y5674D01*
Y5706D01*
Y5739D01*
Y5771D01*
Y5803D01*
Y5835D01*
Y5868D01*
Y5900D01*
Y5932D01*
Y5965D01*
Y5997D01*
Y6029D01*
Y6061D01*
Y6094D01*
Y6126D01*
Y6158D01*
Y6190D01*
Y6223D01*
Y6255D01*
Y6287D01*
Y6319D01*
Y6352D01*
Y6384D01*
Y6416D01*
Y6448D01*
Y6481D01*
Y6513D01*
Y6545D01*
Y6577D01*
Y6610D01*
Y6642D01*
Y6674D01*
Y6707D01*
Y6739D01*
Y6771D01*
Y6803D01*
Y6836D01*
Y6868D01*
Y6900D01*
Y6932D01*
Y6965D01*
Y6997D01*
Y7029D01*
Y7062D01*
Y7094D01*
Y7126D01*
Y7158D01*
Y7191D01*
Y7223D01*
Y7255D01*
Y7287D01*
Y7320D01*
Y7352D01*
Y7384D01*
Y7416D01*
Y7449D01*
Y7481D01*
Y7513D01*
Y7545D01*
Y7578D01*
Y7610D01*
Y7642D01*
Y7674D01*
Y7707D01*
Y7739D01*
Y7771D01*
Y7803D01*
Y7836D01*
Y7868D01*
Y7900D01*
Y7932D01*
Y7965D01*
Y7997D01*
Y8029D01*
Y8062D01*
Y8094D01*
Y8126D01*
Y8158D01*
Y8191D01*
Y8223D01*
Y8255D01*
Y8287D01*
Y8320D01*
Y8352D01*
Y8384D01*
Y8416D01*
Y8449D01*
Y8481D01*
Y8513D01*
Y8546D01*
Y8578D01*
Y8610D01*
Y8642D01*
Y8675D01*
Y8707D01*
Y8739D01*
Y8771D01*
Y8804D01*
Y8836D01*
Y8868D01*
Y8900D01*
Y8933D01*
Y8965D01*
Y8997D01*
Y9029D01*
Y9062D01*
Y9094D01*
Y9126D01*
Y9159D01*
Y9191D01*
Y9223D01*
Y9255D01*
Y9287D01*
Y9320D01*
Y9352D01*
Y9384D01*
Y9417D01*
Y9449D01*
Y9481D01*
Y9513D01*
Y9546D01*
Y9578D01*
Y9610D01*
Y9642D01*
Y9675D01*
Y9707D01*
Y9739D01*
Y9771D01*
Y9804D01*
Y9836D01*
Y9868D01*
Y9900D01*
Y9933D01*
Y9965D01*
Y9997D01*
Y10029D01*
Y10062D01*
Y10094D01*
Y10126D01*
Y10159D01*
Y10191D01*
Y10223D01*
Y10255D01*
Y10288D01*
Y10320D01*
Y10352D01*
Y10384D01*
Y10417D01*
Y10449D01*
Y10481D01*
Y10514D01*
Y10546D01*
Y10578D01*
Y10610D01*
Y10643D01*
Y10675D01*
Y10707D01*
Y10739D01*
Y10772D01*
Y10804D01*
Y10836D01*
Y10868D01*
Y10901D01*
Y10933D01*
Y10965D01*
Y10997D01*
Y11030D01*
Y11062D01*
Y11094D01*
Y11126D01*
Y11159D01*
Y11191D01*
Y11223D01*
Y11255D01*
Y11288D01*
Y11320D01*
Y11352D01*
Y11384D01*
Y11417D01*
Y11449D01*
Y11481D01*
Y11514D01*
Y11546D01*
Y11578D01*
Y11610D01*
Y11643D01*
Y11675D01*
Y11707D01*
Y11739D01*
Y11772D01*
Y11804D01*
Y11836D01*
Y11868D01*
Y11901D01*
Y11933D01*
Y11965D01*
Y11998D01*
Y12030D01*
Y12062D01*
Y12094D01*
Y12127D01*
Y12159D01*
Y12191D01*
Y12223D01*
Y12256D01*
Y12288D01*
Y12320D01*
Y12352D01*
Y12385D01*
Y12417D01*
Y12449D01*
Y12481D01*
Y12514D01*
X457846D01*
Y12546D01*
Y12578D01*
Y12610D01*
Y12643D01*
Y12675D01*
X457814D01*
Y12707D01*
Y12740D01*
X457782D01*
Y12772D01*
Y12804D01*
X457749D01*
Y12836D01*
Y12869D01*
X457717D01*
Y12901D01*
X457685D01*
Y12933D01*
Y12965D01*
X457653D01*
Y12998D01*
X457620D01*
Y13030D01*
X457588D01*
Y13062D01*
X457523D01*
Y13094D01*
X457491D01*
Y13127D01*
X457427D01*
Y13159D01*
X457362D01*
Y13191D01*
X457298D01*
Y13223D01*
X457168D01*
Y13256D01*
X453071D01*
Y13288D01*
Y13320D01*
Y13352D01*
Y13385D01*
Y13417D01*
Y13449D01*
Y13482D01*
Y13514D01*
Y13546D01*
Y13578D01*
Y13611D01*
Y13643D01*
Y13675D01*
Y13707D01*
Y13740D01*
Y13772D01*
Y13804D01*
Y13836D01*
Y13869D01*
Y13901D01*
Y13933D01*
Y13965D01*
Y13998D01*
Y14030D01*
Y14062D01*
Y14095D01*
Y14127D01*
Y14159D01*
Y14191D01*
Y14224D01*
Y14256D01*
Y14288D01*
Y14320D01*
Y14353D01*
Y14385D01*
Y14417D01*
Y14449D01*
Y14482D01*
X457168D01*
Y14449D01*
D02*
G37*
G36*
X58465Y-23228D02*
X56693D01*
X54921Y-21457D01*
Y-19291D01*
X58465D01*
Y-23228D01*
D02*
G37*
G36*
X187008Y-97835D02*
X186221D01*
Y-96457D01*
X185827D01*
Y-95866D01*
X187008D01*
Y-97835D01*
D02*
G37*
G36*
X429331Y-143898D02*
Y-146063D01*
X425787D01*
Y-142126D01*
X427559D01*
X429331Y-143898D01*
D02*
G37*
G36*
X279134Y-198622D02*
X278346D01*
Y-197244D01*
X277953D01*
Y-196653D01*
X279134D01*
Y-198622D01*
D02*
G37*
G36*
X324213Y-237008D02*
X322244D01*
Y-236221D01*
X323622D01*
Y-235827D01*
X324213D01*
Y-237008D01*
D02*
G37*
G36*
X478937Y-262992D02*
X476968D01*
Y-262205D01*
X478346D01*
Y-261811D01*
X478937D01*
Y-262992D01*
D02*
G37*
G36*
X337992Y-290158D02*
X336024D01*
Y-289370D01*
X337402D01*
Y-288976D01*
X337992D01*
Y-290158D01*
D02*
G37*
G36*
X319094Y-290945D02*
X317126D01*
Y-290158D01*
X318504D01*
Y-289764D01*
X319094D01*
Y-290945D01*
D02*
G37*
%LPC*%
G36*
X486849Y6610D02*
X486753D01*
Y6577D01*
X486720D01*
Y6610D01*
X482946D01*
Y6577D01*
X482784D01*
Y6545D01*
X482688D01*
Y6513D01*
X482623D01*
Y6481D01*
X482591D01*
Y6448D01*
X482559D01*
Y6416D01*
X482526D01*
Y6384D01*
X482494D01*
Y6352D01*
X482462D01*
Y6319D01*
X482430D01*
Y6287D01*
X482397D01*
Y6255D01*
X482365D01*
Y6223D01*
X482333D01*
Y6190D01*
X482301D01*
Y6158D01*
X482268D01*
Y6126D01*
X482236D01*
Y6094D01*
X482204D01*
Y6061D01*
X482171D01*
Y6029D01*
X482139D01*
Y5997D01*
X482107D01*
Y5965D01*
X482075D01*
Y5932D01*
X482042D01*
Y5900D01*
X482010D01*
Y5868D01*
X481978D01*
Y5835D01*
X481946D01*
Y5803D01*
X481913D01*
Y5771D01*
X481881D01*
Y5739D01*
X481849D01*
Y5706D01*
X481816D01*
Y5674D01*
X481784D01*
Y5642D01*
X481752D01*
Y5610D01*
X481720D01*
Y5577D01*
X481687D01*
Y5545D01*
Y5513D01*
Y5481D01*
X481655D01*
Y5448D01*
Y5416D01*
Y5384D01*
Y5352D01*
Y5319D01*
X481623D01*
Y5287D01*
Y5255D01*
Y5223D01*
Y5190D01*
Y5158D01*
Y5126D01*
Y5094D01*
Y5061D01*
Y5029D01*
Y4997D01*
Y4964D01*
Y4932D01*
Y4900D01*
Y4868D01*
Y4835D01*
Y4803D01*
Y4771D01*
Y4739D01*
Y4706D01*
Y4674D01*
Y4642D01*
Y4610D01*
Y4577D01*
Y4545D01*
Y4513D01*
Y4481D01*
Y4448D01*
Y4416D01*
Y4384D01*
Y4352D01*
Y4319D01*
Y4287D01*
Y4255D01*
Y4222D01*
Y4190D01*
Y4158D01*
Y4126D01*
Y4093D01*
Y4061D01*
Y4029D01*
Y3997D01*
Y3964D01*
Y3932D01*
Y3900D01*
Y3867D01*
Y3835D01*
Y3803D01*
Y3771D01*
Y3739D01*
Y3706D01*
Y3674D01*
Y3642D01*
Y3609D01*
Y3577D01*
Y3545D01*
Y3513D01*
Y3480D01*
Y3448D01*
Y3416D01*
Y3384D01*
Y3351D01*
Y3319D01*
Y3287D01*
Y3255D01*
Y3222D01*
Y3190D01*
Y3158D01*
Y3125D01*
Y3093D01*
Y3061D01*
Y3029D01*
Y2997D01*
Y2964D01*
Y2932D01*
Y2900D01*
Y2867D01*
Y2835D01*
Y2803D01*
Y2771D01*
Y2738D01*
Y2706D01*
Y2674D01*
Y2642D01*
Y2609D01*
Y2577D01*
Y2545D01*
Y2513D01*
Y2480D01*
Y2448D01*
Y2416D01*
Y2383D01*
Y2351D01*
Y2319D01*
Y2287D01*
Y2254D01*
Y2222D01*
Y2190D01*
Y2158D01*
Y2125D01*
Y2093D01*
Y2061D01*
Y2029D01*
Y1996D01*
Y1964D01*
Y1932D01*
Y1900D01*
Y1867D01*
Y1835D01*
Y1803D01*
Y1770D01*
Y1738D01*
Y1706D01*
Y1674D01*
Y1641D01*
Y1609D01*
Y1577D01*
Y1545D01*
Y1512D01*
Y1480D01*
Y1448D01*
Y1416D01*
Y1383D01*
Y1351D01*
Y1319D01*
Y1287D01*
Y1254D01*
Y1222D01*
Y1190D01*
Y1158D01*
Y1125D01*
Y1093D01*
Y1061D01*
Y1029D01*
Y996D01*
Y964D01*
Y932D01*
Y900D01*
Y867D01*
Y835D01*
X481655D01*
Y803D01*
Y770D01*
Y738D01*
Y706D01*
Y674D01*
X481687D01*
Y641D01*
Y609D01*
X481720D01*
Y577D01*
Y545D01*
X481752D01*
Y512D01*
X481784D01*
Y480D01*
X481816D01*
Y448D01*
X481849D01*
Y416D01*
X481881D01*
Y383D01*
X481913D01*
Y351D01*
X481946D01*
Y319D01*
X481978D01*
Y286D01*
X482010D01*
Y254D01*
X482042D01*
Y222D01*
X482075D01*
Y190D01*
X482107D01*
Y157D01*
X482139D01*
Y125D01*
X482171D01*
Y93D01*
X482204D01*
Y61D01*
X482236D01*
Y28D01*
X482268D01*
Y-4D01*
X482301D01*
Y-36D01*
X482333D01*
Y-68D01*
X482365D01*
Y-101D01*
X482397D01*
Y-133D01*
X482430D01*
Y-165D01*
X482462D01*
Y-197D01*
X482494D01*
Y-230D01*
X482526D01*
Y-262D01*
X482559D01*
Y-294D01*
X482591D01*
Y-326D01*
X482623D01*
Y-359D01*
X482688D01*
Y-391D01*
X482817D01*
Y-423D01*
X486914D01*
Y-391D01*
X486946D01*
Y-359D01*
X486978D01*
Y-326D01*
Y-294D01*
X487011D01*
Y-262D01*
Y-230D01*
Y-197D01*
Y-165D01*
Y-133D01*
Y-101D01*
Y-68D01*
Y-36D01*
Y-4D01*
Y28D01*
Y61D01*
Y93D01*
Y125D01*
Y157D01*
Y190D01*
Y222D01*
Y254D01*
Y286D01*
Y319D01*
Y351D01*
Y383D01*
Y416D01*
Y448D01*
Y480D01*
Y512D01*
Y545D01*
Y577D01*
Y609D01*
Y641D01*
Y674D01*
Y706D01*
Y738D01*
Y770D01*
Y803D01*
Y835D01*
Y867D01*
Y900D01*
Y932D01*
Y964D01*
Y996D01*
Y1029D01*
Y1061D01*
Y1093D01*
X486978D01*
Y1125D01*
Y1158D01*
X486946D01*
Y1190D01*
X486882D01*
Y1222D01*
X483430D01*
Y1254D01*
X483397D01*
Y1287D01*
Y1319D01*
Y1351D01*
Y1383D01*
Y1416D01*
Y1448D01*
Y1480D01*
Y1512D01*
Y1545D01*
Y1577D01*
Y1609D01*
Y1641D01*
Y1674D01*
Y1706D01*
Y1738D01*
Y1770D01*
Y1803D01*
Y1835D01*
Y1867D01*
Y1900D01*
Y1932D01*
Y1964D01*
Y1996D01*
Y2029D01*
Y2061D01*
Y2093D01*
Y2125D01*
Y2158D01*
Y2190D01*
Y2222D01*
Y2254D01*
Y2287D01*
Y2319D01*
Y2351D01*
X483430D01*
Y2383D01*
X486398D01*
Y2416D01*
X486462D01*
Y2448D01*
Y2480D01*
X486494D01*
Y2513D01*
Y2545D01*
Y2577D01*
Y2609D01*
Y2642D01*
Y2674D01*
Y2706D01*
Y2738D01*
Y2771D01*
Y2803D01*
Y2835D01*
Y2867D01*
Y2900D01*
Y2932D01*
Y2964D01*
Y2997D01*
Y3029D01*
Y3061D01*
Y3093D01*
Y3125D01*
Y3158D01*
Y3190D01*
Y3222D01*
Y3255D01*
Y3287D01*
Y3319D01*
Y3351D01*
Y3384D01*
Y3416D01*
Y3448D01*
Y3480D01*
Y3513D01*
Y3545D01*
Y3577D01*
Y3609D01*
Y3642D01*
Y3674D01*
X486462D01*
Y3706D01*
Y3739D01*
X486398D01*
Y3771D01*
X483430D01*
Y3803D01*
X483397D01*
Y3835D01*
Y3867D01*
Y3900D01*
Y3932D01*
Y3964D01*
Y3997D01*
Y4029D01*
Y4061D01*
Y4093D01*
Y4126D01*
Y4158D01*
Y4190D01*
Y4222D01*
Y4255D01*
Y4287D01*
Y4319D01*
Y4352D01*
Y4384D01*
Y4416D01*
Y4448D01*
Y4481D01*
Y4513D01*
Y4545D01*
Y4577D01*
Y4610D01*
Y4642D01*
Y4674D01*
Y4706D01*
Y4739D01*
Y4771D01*
Y4803D01*
Y4835D01*
Y4868D01*
Y4900D01*
Y4932D01*
X483430D01*
Y4964D01*
X486914D01*
Y4997D01*
X486946D01*
Y5029D01*
X486978D01*
Y5061D01*
X487011D01*
Y5094D01*
Y5126D01*
Y5158D01*
Y5190D01*
Y5223D01*
Y5255D01*
Y5287D01*
Y5319D01*
Y5352D01*
Y5384D01*
Y5416D01*
Y5448D01*
Y5481D01*
Y5513D01*
Y5545D01*
Y5577D01*
Y5610D01*
Y5642D01*
Y5674D01*
Y5706D01*
Y5739D01*
Y5771D01*
Y5803D01*
Y5835D01*
Y5868D01*
Y5900D01*
Y5932D01*
Y5965D01*
Y5997D01*
Y6029D01*
Y6061D01*
Y6094D01*
Y6126D01*
Y6158D01*
Y6190D01*
Y6223D01*
Y6255D01*
Y6287D01*
Y6319D01*
Y6352D01*
Y6384D01*
Y6416D01*
Y6448D01*
X486978D01*
Y6481D01*
Y6513D01*
X486946D01*
Y6545D01*
X486914D01*
Y6577D01*
X486849D01*
Y6610D01*
D02*
G37*
G36*
X470331D02*
X470267D01*
Y6577D01*
X470235D01*
Y6610D01*
X465266D01*
Y6577D01*
X465169D01*
Y6545D01*
X465137D01*
Y6513D01*
Y6481D01*
X465105D01*
Y6448D01*
Y6416D01*
Y6384D01*
Y6352D01*
Y6319D01*
Y6287D01*
Y6255D01*
Y6223D01*
Y6190D01*
Y6158D01*
Y6126D01*
Y6094D01*
Y6061D01*
Y6029D01*
Y5997D01*
Y5965D01*
Y5932D01*
Y5900D01*
Y5868D01*
Y5835D01*
Y5803D01*
Y5771D01*
Y5739D01*
Y5706D01*
Y5674D01*
Y5642D01*
Y5610D01*
Y5577D01*
Y5545D01*
Y5513D01*
Y5481D01*
Y5448D01*
Y5416D01*
Y5384D01*
Y5352D01*
Y5319D01*
Y5287D01*
Y5255D01*
Y5223D01*
Y5190D01*
Y5158D01*
Y5126D01*
Y5094D01*
Y5061D01*
Y5029D01*
Y4997D01*
X465137D01*
Y4964D01*
X465169D01*
Y4932D01*
X465202D01*
Y4900D01*
X465266D01*
Y4868D01*
X466815D01*
Y4835D01*
X466847D01*
Y4803D01*
X466879D01*
Y4771D01*
Y4739D01*
X466912D01*
Y4706D01*
Y4674D01*
Y4642D01*
Y4610D01*
Y4577D01*
Y4545D01*
Y4513D01*
Y4481D01*
Y4448D01*
Y4416D01*
Y4384D01*
Y4352D01*
Y4319D01*
Y4287D01*
Y4255D01*
Y4222D01*
Y4190D01*
Y4158D01*
Y4126D01*
Y4093D01*
Y4061D01*
Y4029D01*
Y3997D01*
Y3964D01*
Y3932D01*
Y3900D01*
Y3867D01*
Y3835D01*
Y3803D01*
Y3771D01*
Y3739D01*
Y3706D01*
Y3674D01*
Y3642D01*
Y3609D01*
Y3577D01*
Y3545D01*
Y3513D01*
Y3480D01*
Y3448D01*
Y3416D01*
Y3384D01*
Y3351D01*
Y3319D01*
Y3287D01*
Y3255D01*
Y3222D01*
Y3190D01*
Y3158D01*
Y3125D01*
Y3093D01*
Y3061D01*
Y3029D01*
Y2997D01*
Y2964D01*
Y2932D01*
Y2900D01*
Y2867D01*
Y2835D01*
Y2803D01*
Y2771D01*
Y2738D01*
Y2706D01*
Y2674D01*
Y2642D01*
Y2609D01*
Y2577D01*
Y2545D01*
Y2513D01*
Y2480D01*
Y2448D01*
Y2416D01*
Y2383D01*
Y2351D01*
Y2319D01*
Y2287D01*
Y2254D01*
Y2222D01*
Y2190D01*
Y2158D01*
Y2125D01*
Y2093D01*
Y2061D01*
Y2029D01*
Y1996D01*
Y1964D01*
Y1932D01*
Y1900D01*
Y1867D01*
Y1835D01*
Y1803D01*
Y1770D01*
Y1738D01*
Y1706D01*
Y1674D01*
Y1641D01*
Y1609D01*
Y1577D01*
Y1545D01*
Y1512D01*
Y1480D01*
Y1448D01*
Y1416D01*
Y1383D01*
Y1351D01*
Y1319D01*
Y1287D01*
Y1254D01*
Y1222D01*
Y1190D01*
Y1158D01*
Y1125D01*
Y1093D01*
Y1061D01*
Y1029D01*
Y996D01*
Y964D01*
Y932D01*
Y900D01*
Y867D01*
Y835D01*
Y803D01*
Y770D01*
Y738D01*
Y706D01*
Y674D01*
Y641D01*
Y609D01*
Y577D01*
Y545D01*
Y512D01*
Y480D01*
Y448D01*
Y416D01*
Y383D01*
Y351D01*
Y319D01*
Y286D01*
Y254D01*
Y222D01*
Y190D01*
Y157D01*
Y125D01*
Y93D01*
Y61D01*
Y28D01*
Y-4D01*
Y-36D01*
Y-68D01*
Y-101D01*
Y-133D01*
Y-165D01*
Y-197D01*
Y-230D01*
Y-262D01*
Y-294D01*
Y-326D01*
X466944D01*
Y-359D01*
X466976D01*
Y-391D01*
X467008D01*
Y-423D01*
X468589D01*
Y-391D01*
X468621D01*
Y-359D01*
X468654D01*
Y-326D01*
Y-294D01*
Y-262D01*
X468686D01*
Y-230D01*
Y-197D01*
Y-165D01*
Y-133D01*
Y-101D01*
Y-68D01*
Y-36D01*
Y-4D01*
Y28D01*
Y61D01*
Y93D01*
Y125D01*
Y157D01*
Y190D01*
Y222D01*
Y254D01*
Y286D01*
Y319D01*
Y351D01*
Y383D01*
Y416D01*
Y448D01*
Y480D01*
Y512D01*
Y545D01*
Y577D01*
Y609D01*
Y641D01*
Y674D01*
Y706D01*
Y738D01*
Y770D01*
Y803D01*
Y835D01*
Y867D01*
Y900D01*
Y932D01*
Y964D01*
Y996D01*
Y1029D01*
Y1061D01*
Y1093D01*
Y1125D01*
Y1158D01*
Y1190D01*
Y1222D01*
Y1254D01*
Y1287D01*
Y1319D01*
Y1351D01*
Y1383D01*
Y1416D01*
Y1448D01*
Y1480D01*
Y1512D01*
Y1545D01*
Y1577D01*
Y1609D01*
Y1641D01*
Y1674D01*
Y1706D01*
Y1738D01*
Y1770D01*
Y1803D01*
Y1835D01*
Y1867D01*
Y1900D01*
Y1932D01*
Y1964D01*
Y1996D01*
Y2029D01*
Y2061D01*
Y2093D01*
Y2125D01*
Y2158D01*
Y2190D01*
Y2222D01*
Y2254D01*
Y2287D01*
Y2319D01*
Y2351D01*
Y2383D01*
Y2416D01*
Y2448D01*
Y2480D01*
Y2513D01*
Y2545D01*
Y2577D01*
Y2609D01*
Y2642D01*
Y2674D01*
Y2706D01*
Y2738D01*
Y2771D01*
Y2803D01*
Y2835D01*
Y2867D01*
Y2900D01*
Y2932D01*
Y2964D01*
Y2997D01*
Y3029D01*
Y3061D01*
Y3093D01*
Y3125D01*
Y3158D01*
Y3190D01*
Y3222D01*
Y3255D01*
Y3287D01*
Y3319D01*
Y3351D01*
Y3384D01*
Y3416D01*
Y3448D01*
Y3480D01*
Y3513D01*
Y3545D01*
Y3577D01*
Y3609D01*
Y3642D01*
Y3674D01*
Y3706D01*
Y3739D01*
Y3771D01*
Y3803D01*
Y3835D01*
Y3867D01*
Y3900D01*
Y3932D01*
Y3964D01*
Y3997D01*
Y4029D01*
Y4061D01*
Y4093D01*
Y4126D01*
Y4158D01*
Y4190D01*
Y4222D01*
Y4255D01*
Y4287D01*
Y4319D01*
Y4352D01*
Y4384D01*
Y4416D01*
Y4448D01*
Y4481D01*
Y4513D01*
Y4545D01*
Y4577D01*
Y4610D01*
Y4642D01*
Y4674D01*
Y4706D01*
Y4739D01*
Y4771D01*
Y4803D01*
X468718D01*
Y4835D01*
X468750D01*
Y4868D01*
X470299D01*
Y4900D01*
X470396D01*
Y4932D01*
X470428D01*
Y4964D01*
X470460D01*
Y4997D01*
Y5029D01*
Y5061D01*
X470493D01*
Y5094D01*
Y5126D01*
Y5158D01*
Y5190D01*
Y5223D01*
Y5255D01*
Y5287D01*
Y5319D01*
Y5352D01*
Y5384D01*
Y5416D01*
Y5448D01*
Y5481D01*
Y5513D01*
Y5545D01*
Y5577D01*
Y5610D01*
Y5642D01*
Y5674D01*
Y5706D01*
Y5739D01*
Y5771D01*
Y5803D01*
Y5835D01*
Y5868D01*
Y5900D01*
Y5932D01*
Y5965D01*
Y5997D01*
Y6029D01*
Y6061D01*
Y6094D01*
Y6126D01*
Y6158D01*
Y6190D01*
Y6223D01*
Y6255D01*
Y6287D01*
Y6319D01*
Y6352D01*
Y6384D01*
Y6416D01*
X470460D01*
Y6448D01*
Y6481D01*
Y6513D01*
X470428D01*
Y6545D01*
X470396D01*
Y6577D01*
X470331D01*
Y6610D01*
D02*
G37*
G36*
X478558D02*
X473622D01*
Y6577D01*
X473525D01*
Y6545D01*
X473493D01*
Y6513D01*
Y6481D01*
X473461D01*
Y6448D01*
Y6416D01*
Y6384D01*
Y6352D01*
Y6319D01*
Y6287D01*
Y6255D01*
Y6223D01*
Y6190D01*
Y6158D01*
Y6126D01*
Y6094D01*
Y6061D01*
Y6029D01*
Y5997D01*
Y5965D01*
Y5932D01*
Y5900D01*
Y5868D01*
Y5835D01*
Y5803D01*
Y5771D01*
Y5739D01*
Y5706D01*
Y5674D01*
Y5642D01*
Y5610D01*
Y5577D01*
Y5545D01*
Y5513D01*
Y5481D01*
Y5448D01*
Y5416D01*
Y5384D01*
Y5352D01*
Y5319D01*
Y5287D01*
Y5255D01*
Y5223D01*
Y5190D01*
Y5158D01*
Y5126D01*
Y5094D01*
Y5061D01*
Y5029D01*
Y4997D01*
Y4964D01*
Y4932D01*
Y4900D01*
Y4868D01*
Y4835D01*
Y4803D01*
Y4771D01*
Y4739D01*
Y4706D01*
Y4674D01*
Y4642D01*
Y4610D01*
Y4577D01*
Y4545D01*
Y4513D01*
Y4481D01*
Y4448D01*
Y4416D01*
Y4384D01*
Y4352D01*
Y4319D01*
Y4287D01*
Y4255D01*
Y4222D01*
Y4190D01*
Y4158D01*
Y4126D01*
Y4093D01*
Y4061D01*
Y4029D01*
Y3997D01*
Y3964D01*
Y3932D01*
Y3900D01*
Y3867D01*
Y3835D01*
Y3803D01*
Y3771D01*
Y3739D01*
Y3706D01*
Y3674D01*
Y3642D01*
Y3609D01*
Y3577D01*
Y3545D01*
Y3513D01*
Y3480D01*
Y3448D01*
Y3416D01*
Y3384D01*
Y3351D01*
Y3319D01*
Y3287D01*
Y3255D01*
Y3222D01*
Y3190D01*
Y3158D01*
Y3125D01*
Y3093D01*
Y3061D01*
Y3029D01*
Y2997D01*
Y2964D01*
Y2932D01*
Y2900D01*
Y2867D01*
Y2835D01*
Y2803D01*
Y2771D01*
Y2738D01*
Y2706D01*
Y2674D01*
Y2642D01*
Y2609D01*
Y2577D01*
Y2545D01*
Y2513D01*
Y2480D01*
Y2448D01*
Y2416D01*
Y2383D01*
Y2351D01*
Y2319D01*
Y2287D01*
Y2254D01*
Y2222D01*
Y2190D01*
Y2158D01*
Y2125D01*
Y2093D01*
Y2061D01*
Y2029D01*
Y1996D01*
Y1964D01*
Y1932D01*
Y1900D01*
Y1867D01*
Y1835D01*
Y1803D01*
Y1770D01*
Y1738D01*
Y1706D01*
Y1674D01*
Y1641D01*
Y1609D01*
Y1577D01*
Y1545D01*
Y1512D01*
Y1480D01*
Y1448D01*
Y1416D01*
Y1383D01*
Y1351D01*
Y1319D01*
Y1287D01*
Y1254D01*
Y1222D01*
Y1190D01*
Y1158D01*
Y1125D01*
Y1093D01*
Y1061D01*
Y1029D01*
Y996D01*
Y964D01*
Y932D01*
Y900D01*
Y867D01*
Y835D01*
Y803D01*
Y770D01*
Y738D01*
Y706D01*
Y674D01*
Y641D01*
Y609D01*
Y577D01*
Y545D01*
Y512D01*
Y480D01*
Y448D01*
Y416D01*
Y383D01*
Y351D01*
Y319D01*
Y286D01*
Y254D01*
Y222D01*
Y190D01*
Y157D01*
Y125D01*
Y93D01*
Y61D01*
Y28D01*
Y-4D01*
Y-36D01*
Y-68D01*
Y-101D01*
Y-133D01*
Y-165D01*
Y-197D01*
Y-230D01*
Y-262D01*
Y-294D01*
Y-326D01*
X473493D01*
Y-359D01*
Y-391D01*
X473558D01*
Y-423D01*
X475138D01*
Y-391D01*
X475171D01*
Y-359D01*
X475203D01*
Y-326D01*
Y-294D01*
X475235D01*
Y-262D01*
Y-230D01*
Y-197D01*
Y-165D01*
Y-133D01*
Y-101D01*
Y-68D01*
Y-36D01*
Y-4D01*
Y28D01*
Y61D01*
Y93D01*
Y125D01*
Y157D01*
Y190D01*
Y222D01*
Y254D01*
Y286D01*
Y319D01*
Y351D01*
Y383D01*
Y416D01*
Y448D01*
Y480D01*
Y512D01*
Y545D01*
Y577D01*
Y609D01*
Y641D01*
Y674D01*
Y706D01*
Y738D01*
Y770D01*
Y803D01*
Y835D01*
Y867D01*
Y900D01*
Y932D01*
Y964D01*
Y996D01*
Y1029D01*
Y1061D01*
Y1093D01*
Y1125D01*
Y1158D01*
Y1190D01*
Y1222D01*
Y1254D01*
Y1287D01*
Y1319D01*
Y1351D01*
Y1383D01*
Y1416D01*
Y1448D01*
Y1480D01*
Y1512D01*
Y1545D01*
Y1577D01*
Y1609D01*
Y1641D01*
Y1674D01*
Y1706D01*
Y1738D01*
Y1770D01*
Y1803D01*
Y1835D01*
Y1867D01*
Y1900D01*
Y1932D01*
Y1964D01*
Y1996D01*
Y2029D01*
Y2061D01*
Y2093D01*
Y2125D01*
Y2158D01*
Y2190D01*
Y2222D01*
Y2254D01*
Y2287D01*
Y2319D01*
Y2351D01*
Y2383D01*
Y2416D01*
Y2448D01*
Y2480D01*
Y2513D01*
Y2545D01*
Y2577D01*
Y2609D01*
Y2642D01*
Y2674D01*
Y2706D01*
Y2738D01*
Y2771D01*
Y2803D01*
Y2835D01*
Y2867D01*
Y2900D01*
Y2932D01*
Y2964D01*
Y2997D01*
Y3029D01*
Y3061D01*
Y3093D01*
Y3125D01*
Y3158D01*
Y3190D01*
Y3222D01*
Y3255D01*
Y3287D01*
Y3319D01*
Y3351D01*
Y3384D01*
Y3416D01*
Y3448D01*
Y3480D01*
Y3513D01*
Y3545D01*
Y3577D01*
Y3609D01*
Y3642D01*
Y3674D01*
Y3706D01*
Y3739D01*
Y3771D01*
Y3803D01*
Y3835D01*
Y3867D01*
Y3900D01*
Y3932D01*
Y3964D01*
Y3997D01*
Y4029D01*
Y4061D01*
Y4093D01*
Y4126D01*
Y4158D01*
Y4190D01*
Y4222D01*
Y4255D01*
Y4287D01*
Y4319D01*
Y4352D01*
Y4384D01*
Y4416D01*
Y4448D01*
Y4481D01*
Y4513D01*
Y4545D01*
Y4577D01*
Y4610D01*
Y4642D01*
Y4674D01*
Y4706D01*
Y4739D01*
Y4771D01*
Y4803D01*
Y4835D01*
Y4868D01*
X476332D01*
Y4835D01*
Y4803D01*
Y4771D01*
Y4739D01*
Y4706D01*
Y4674D01*
Y4642D01*
Y4610D01*
Y4577D01*
Y4545D01*
Y4513D01*
Y4481D01*
Y4448D01*
Y4416D01*
Y4384D01*
Y4352D01*
Y4319D01*
Y4287D01*
Y4255D01*
Y4222D01*
Y4190D01*
Y4158D01*
Y4126D01*
Y4093D01*
Y4061D01*
Y4029D01*
Y3997D01*
Y3964D01*
Y3932D01*
Y3900D01*
Y3867D01*
Y3835D01*
Y3803D01*
Y3771D01*
Y3739D01*
Y3706D01*
Y3674D01*
Y3642D01*
Y3609D01*
Y3577D01*
Y3545D01*
Y3513D01*
Y3480D01*
Y3448D01*
Y3416D01*
Y3384D01*
Y3351D01*
Y3319D01*
Y3287D01*
Y3255D01*
Y3222D01*
Y3190D01*
Y3158D01*
Y3125D01*
Y3093D01*
Y3061D01*
Y3029D01*
Y2997D01*
Y2964D01*
Y2932D01*
Y2900D01*
Y2867D01*
Y2835D01*
Y2803D01*
Y2771D01*
Y2738D01*
Y2706D01*
Y2674D01*
Y2642D01*
Y2609D01*
Y2577D01*
Y2545D01*
Y2513D01*
Y2480D01*
Y2448D01*
Y2416D01*
Y2383D01*
Y2351D01*
Y2319D01*
Y2287D01*
Y2254D01*
Y2222D01*
Y2190D01*
Y2158D01*
Y2125D01*
Y2093D01*
Y2061D01*
Y2029D01*
Y1996D01*
Y1964D01*
Y1932D01*
Y1900D01*
Y1867D01*
Y1835D01*
Y1803D01*
Y1770D01*
Y1738D01*
Y1706D01*
Y1674D01*
Y1641D01*
Y1609D01*
Y1577D01*
Y1545D01*
Y1512D01*
Y1480D01*
Y1448D01*
Y1416D01*
Y1383D01*
Y1351D01*
Y1319D01*
Y1287D01*
Y1254D01*
Y1222D01*
Y1190D01*
Y1158D01*
Y1125D01*
Y1093D01*
Y1061D01*
Y1029D01*
Y996D01*
Y964D01*
Y932D01*
Y900D01*
Y867D01*
Y835D01*
Y803D01*
Y770D01*
Y738D01*
Y706D01*
Y674D01*
Y641D01*
Y609D01*
Y577D01*
Y545D01*
Y512D01*
Y480D01*
Y448D01*
Y416D01*
Y383D01*
Y351D01*
Y319D01*
Y286D01*
Y254D01*
Y222D01*
Y190D01*
Y157D01*
Y125D01*
Y93D01*
Y61D01*
Y28D01*
Y-4D01*
Y-36D01*
Y-68D01*
Y-101D01*
Y-133D01*
Y-165D01*
Y-197D01*
Y-230D01*
Y-262D01*
Y-294D01*
X476364D01*
Y-326D01*
Y-359D01*
X476397D01*
Y-391D01*
X476461D01*
Y-423D01*
X477881D01*
Y-391D01*
X477913D01*
Y-359D01*
X477945D01*
Y-326D01*
X477977D01*
Y-294D01*
Y-262D01*
Y-230D01*
Y-197D01*
Y-165D01*
Y-133D01*
Y-101D01*
Y-68D01*
Y-36D01*
Y-4D01*
Y28D01*
Y61D01*
Y93D01*
Y125D01*
Y157D01*
Y190D01*
Y222D01*
Y254D01*
Y286D01*
Y319D01*
Y351D01*
Y383D01*
Y416D01*
Y448D01*
Y480D01*
Y512D01*
Y545D01*
Y577D01*
Y609D01*
Y641D01*
Y674D01*
Y706D01*
Y738D01*
Y770D01*
Y803D01*
Y835D01*
Y867D01*
Y900D01*
Y932D01*
Y964D01*
Y996D01*
Y1029D01*
Y1061D01*
Y1093D01*
Y1125D01*
Y1158D01*
Y1190D01*
Y1222D01*
Y1254D01*
Y1287D01*
Y1319D01*
Y1351D01*
Y1383D01*
Y1416D01*
Y1448D01*
Y1480D01*
Y1512D01*
Y1545D01*
Y1577D01*
Y1609D01*
Y1641D01*
Y1674D01*
Y1706D01*
Y1738D01*
Y1770D01*
Y1803D01*
Y1835D01*
Y1867D01*
Y1900D01*
Y1932D01*
Y1964D01*
Y1996D01*
Y2029D01*
Y2061D01*
Y2093D01*
Y2125D01*
Y2158D01*
Y2190D01*
Y2222D01*
Y2254D01*
Y2287D01*
Y2319D01*
Y2351D01*
Y2383D01*
Y2416D01*
Y2448D01*
Y2480D01*
Y2513D01*
Y2545D01*
Y2577D01*
Y2609D01*
Y2642D01*
Y2674D01*
Y2706D01*
Y2738D01*
Y2771D01*
Y2803D01*
Y2835D01*
Y2867D01*
Y2900D01*
Y2932D01*
Y2964D01*
Y2997D01*
Y3029D01*
Y3061D01*
Y3093D01*
Y3125D01*
Y3158D01*
Y3190D01*
Y3222D01*
Y3255D01*
Y3287D01*
Y3319D01*
Y3351D01*
Y3384D01*
Y3416D01*
Y3448D01*
Y3480D01*
Y3513D01*
Y3545D01*
Y3577D01*
Y3609D01*
Y3642D01*
Y3674D01*
Y3706D01*
Y3739D01*
Y3771D01*
Y3803D01*
Y3835D01*
Y3867D01*
Y3900D01*
Y3932D01*
Y3964D01*
Y3997D01*
Y4029D01*
Y4061D01*
Y4093D01*
Y4126D01*
Y4158D01*
Y4190D01*
Y4222D01*
Y4255D01*
Y4287D01*
Y4319D01*
Y4352D01*
Y4384D01*
Y4416D01*
Y4448D01*
Y4481D01*
Y4513D01*
Y4545D01*
Y4577D01*
Y4610D01*
Y4642D01*
Y4674D01*
Y4706D01*
Y4739D01*
Y4771D01*
Y4803D01*
Y4835D01*
Y4868D01*
X478429D01*
Y4900D01*
X478461D01*
Y4868D01*
X478558D01*
Y4900D01*
Y4932D01*
Y4964D01*
Y4997D01*
Y5029D01*
Y5061D01*
Y5094D01*
Y5126D01*
Y5158D01*
Y5190D01*
Y5223D01*
Y5255D01*
Y5287D01*
Y5319D01*
Y5352D01*
Y5384D01*
Y5416D01*
Y5448D01*
Y5481D01*
Y5513D01*
Y5545D01*
Y5577D01*
Y5610D01*
Y5642D01*
Y5674D01*
Y5706D01*
Y5739D01*
Y5771D01*
Y5803D01*
Y5835D01*
Y5868D01*
Y5900D01*
Y5932D01*
Y5965D01*
Y5997D01*
Y6029D01*
Y6061D01*
Y6094D01*
Y6126D01*
Y6158D01*
Y6190D01*
Y6223D01*
Y6255D01*
Y6287D01*
Y6319D01*
Y6352D01*
Y6384D01*
Y6416D01*
Y6448D01*
Y6481D01*
Y6513D01*
Y6545D01*
Y6577D01*
Y6610D01*
D02*
G37*
G36*
X472525D02*
X471041D01*
Y6577D01*
X470944D01*
Y6545D01*
Y6513D01*
X470912D01*
Y6481D01*
Y6448D01*
X470880D01*
Y6416D01*
Y6384D01*
Y6352D01*
Y6319D01*
Y6287D01*
Y6255D01*
Y6223D01*
Y6190D01*
Y6158D01*
Y6126D01*
Y6094D01*
Y6061D01*
Y6029D01*
Y5997D01*
Y5965D01*
Y5932D01*
Y5900D01*
Y5868D01*
Y5835D01*
Y5803D01*
Y5771D01*
Y5739D01*
Y5706D01*
Y5674D01*
Y5642D01*
Y5610D01*
Y5577D01*
Y5545D01*
Y5513D01*
Y5481D01*
Y5448D01*
Y5416D01*
Y5384D01*
Y5352D01*
Y5319D01*
Y5287D01*
Y5255D01*
Y5223D01*
Y5190D01*
Y5158D01*
Y5126D01*
Y5094D01*
Y5061D01*
Y5029D01*
Y4997D01*
Y4964D01*
Y4932D01*
Y4900D01*
Y4868D01*
Y4835D01*
Y4803D01*
Y4771D01*
Y4739D01*
Y4706D01*
Y4674D01*
Y4642D01*
Y4610D01*
Y4577D01*
Y4545D01*
Y4513D01*
Y4481D01*
Y4448D01*
Y4416D01*
Y4384D01*
Y4352D01*
Y4319D01*
Y4287D01*
Y4255D01*
Y4222D01*
Y4190D01*
Y4158D01*
Y4126D01*
Y4093D01*
Y4061D01*
Y4029D01*
Y3997D01*
Y3964D01*
Y3932D01*
Y3900D01*
Y3867D01*
Y3835D01*
Y3803D01*
Y3771D01*
Y3739D01*
Y3706D01*
Y3674D01*
Y3642D01*
Y3609D01*
Y3577D01*
Y3545D01*
Y3513D01*
Y3480D01*
Y3448D01*
Y3416D01*
Y3384D01*
Y3351D01*
Y3319D01*
Y3287D01*
Y3255D01*
Y3222D01*
Y3190D01*
Y3158D01*
Y3125D01*
Y3093D01*
Y3061D01*
Y3029D01*
Y2997D01*
Y2964D01*
Y2932D01*
Y2900D01*
Y2867D01*
Y2835D01*
Y2803D01*
Y2771D01*
Y2738D01*
Y2706D01*
Y2674D01*
Y2642D01*
Y2609D01*
Y2577D01*
Y2545D01*
Y2513D01*
Y2480D01*
Y2448D01*
Y2416D01*
Y2383D01*
Y2351D01*
Y2319D01*
Y2287D01*
Y2254D01*
Y2222D01*
Y2190D01*
Y2158D01*
Y2125D01*
Y2093D01*
Y2061D01*
Y2029D01*
Y1996D01*
Y1964D01*
Y1932D01*
Y1900D01*
Y1867D01*
Y1835D01*
Y1803D01*
Y1770D01*
Y1738D01*
Y1706D01*
Y1674D01*
Y1641D01*
Y1609D01*
Y1577D01*
Y1545D01*
Y1512D01*
Y1480D01*
Y1448D01*
Y1416D01*
Y1383D01*
Y1351D01*
Y1319D01*
Y1287D01*
Y1254D01*
Y1222D01*
Y1190D01*
Y1158D01*
Y1125D01*
Y1093D01*
Y1061D01*
Y1029D01*
Y996D01*
Y964D01*
Y932D01*
Y900D01*
Y867D01*
Y835D01*
Y803D01*
Y770D01*
Y738D01*
Y706D01*
Y674D01*
Y641D01*
Y609D01*
Y577D01*
Y545D01*
Y512D01*
Y480D01*
Y448D01*
Y416D01*
Y383D01*
Y351D01*
Y319D01*
Y286D01*
Y254D01*
Y222D01*
Y190D01*
Y157D01*
Y125D01*
Y93D01*
Y61D01*
Y28D01*
Y-4D01*
Y-36D01*
Y-68D01*
Y-101D01*
Y-133D01*
Y-165D01*
Y-197D01*
Y-230D01*
Y-262D01*
Y-294D01*
X470912D01*
Y-326D01*
Y-359D01*
X470944D01*
Y-391D01*
X470977D01*
Y-423D01*
X472590D01*
Y-391D01*
X472622D01*
Y-359D01*
X472654D01*
Y-326D01*
Y-294D01*
Y-262D01*
Y-230D01*
Y-197D01*
Y-165D01*
Y-133D01*
Y-101D01*
Y-68D01*
Y-36D01*
Y-4D01*
Y28D01*
Y61D01*
Y93D01*
Y125D01*
Y157D01*
Y190D01*
Y222D01*
Y254D01*
Y286D01*
Y319D01*
Y351D01*
Y383D01*
Y416D01*
Y448D01*
Y480D01*
Y512D01*
Y545D01*
Y577D01*
Y609D01*
Y641D01*
Y674D01*
Y706D01*
Y738D01*
Y770D01*
Y803D01*
Y835D01*
Y867D01*
Y900D01*
Y932D01*
Y964D01*
Y996D01*
Y1029D01*
Y1061D01*
Y1093D01*
Y1125D01*
Y1158D01*
Y1190D01*
Y1222D01*
Y1254D01*
Y1287D01*
Y1319D01*
Y1351D01*
Y1383D01*
Y1416D01*
Y1448D01*
Y1480D01*
Y1512D01*
Y1545D01*
Y1577D01*
Y1609D01*
Y1641D01*
Y1674D01*
Y1706D01*
Y1738D01*
Y1770D01*
Y1803D01*
Y1835D01*
Y1867D01*
Y1900D01*
Y1932D01*
Y1964D01*
Y1996D01*
Y2029D01*
Y2061D01*
Y2093D01*
Y2125D01*
Y2158D01*
Y2190D01*
Y2222D01*
Y2254D01*
Y2287D01*
Y2319D01*
Y2351D01*
Y2383D01*
Y2416D01*
Y2448D01*
Y2480D01*
Y2513D01*
Y2545D01*
Y2577D01*
Y2609D01*
Y2642D01*
Y2674D01*
Y2706D01*
Y2738D01*
Y2771D01*
Y2803D01*
Y2835D01*
Y2867D01*
Y2900D01*
Y2932D01*
Y2964D01*
Y2997D01*
Y3029D01*
Y3061D01*
Y3093D01*
Y3125D01*
Y3158D01*
Y3190D01*
Y3222D01*
Y3255D01*
Y3287D01*
Y3319D01*
Y3351D01*
Y3384D01*
Y3416D01*
Y3448D01*
Y3480D01*
Y3513D01*
Y3545D01*
Y3577D01*
Y3609D01*
Y3642D01*
Y3674D01*
Y3706D01*
Y3739D01*
Y3771D01*
Y3803D01*
Y3835D01*
Y3867D01*
Y3900D01*
Y3932D01*
Y3964D01*
Y3997D01*
Y4029D01*
Y4061D01*
Y4093D01*
Y4126D01*
Y4158D01*
Y4190D01*
Y4222D01*
Y4255D01*
Y4287D01*
Y4319D01*
Y4352D01*
Y4384D01*
Y4416D01*
Y4448D01*
Y4481D01*
Y4513D01*
Y4545D01*
Y4577D01*
Y4610D01*
Y4642D01*
Y4674D01*
Y4706D01*
Y4739D01*
Y4771D01*
Y4803D01*
Y4835D01*
Y4868D01*
Y4900D01*
Y4932D01*
Y4964D01*
Y4997D01*
Y5029D01*
Y5061D01*
Y5094D01*
Y5126D01*
Y5158D01*
Y5190D01*
Y5223D01*
Y5255D01*
Y5287D01*
Y5319D01*
Y5352D01*
Y5384D01*
Y5416D01*
Y5448D01*
Y5481D01*
Y5513D01*
Y5545D01*
Y5577D01*
Y5610D01*
Y5642D01*
Y5674D01*
Y5706D01*
Y5739D01*
Y5771D01*
Y5803D01*
Y5835D01*
Y5868D01*
Y5900D01*
Y5932D01*
Y5965D01*
Y5997D01*
Y6029D01*
Y6061D01*
Y6094D01*
Y6126D01*
Y6158D01*
Y6190D01*
Y6223D01*
Y6255D01*
Y6287D01*
Y6319D01*
Y6352D01*
Y6384D01*
Y6416D01*
Y6448D01*
Y6481D01*
Y6513D01*
X472622D01*
Y6545D01*
X472590D01*
Y6577D01*
X472525D01*
Y6610D01*
D02*
G37*
G36*
X480784Y11804D02*
X479591D01*
Y11772D01*
X479107D01*
Y11739D01*
X478784D01*
Y11707D01*
X478526D01*
Y11675D01*
X478332D01*
Y11643D01*
X478106D01*
Y11610D01*
X477913D01*
Y11578D01*
X477752D01*
Y11546D01*
X477590D01*
Y11514D01*
X477429D01*
Y11481D01*
X477300D01*
Y11449D01*
X477171D01*
Y11417D01*
X477042D01*
Y11384D01*
X476913D01*
Y11352D01*
X476816D01*
Y11320D01*
X476687D01*
Y11288D01*
X476590D01*
Y11255D01*
X476493D01*
Y11223D01*
X476364D01*
Y11191D01*
X476267D01*
Y11159D01*
X476171D01*
Y11126D01*
X476074D01*
Y11094D01*
X476009D01*
Y11062D01*
X475913D01*
Y11030D01*
X475816D01*
Y10997D01*
X475719D01*
Y10965D01*
X475655D01*
Y10933D01*
X475558D01*
Y10901D01*
X475493D01*
Y10868D01*
X475396D01*
Y10836D01*
X475332D01*
Y10804D01*
X475267D01*
Y10772D01*
X475171D01*
Y10739D01*
X475106D01*
Y10707D01*
X475042D01*
Y10675D01*
X474977D01*
Y10643D01*
X474880D01*
Y10610D01*
X474816D01*
Y10578D01*
X474751D01*
Y10546D01*
X474687D01*
Y10514D01*
X474622D01*
Y10481D01*
X474558D01*
Y10449D01*
X474493D01*
Y10417D01*
X474429D01*
Y10384D01*
X474364D01*
Y10352D01*
X474299D01*
Y10320D01*
X474267D01*
Y10288D01*
X474203D01*
Y10255D01*
X474138D01*
Y10223D01*
X474074D01*
Y10191D01*
X474009D01*
Y10159D01*
X473977D01*
Y10126D01*
X473912D01*
Y10094D01*
X473848D01*
Y10062D01*
X473816D01*
Y10029D01*
X473751D01*
Y9997D01*
X473687D01*
Y9965D01*
X473654D01*
Y9933D01*
X473590D01*
Y9900D01*
X473525D01*
Y9868D01*
X473493D01*
Y9836D01*
X473428D01*
Y9804D01*
X473396D01*
Y9771D01*
X473332D01*
Y9739D01*
X473299D01*
Y9707D01*
X473235D01*
Y9675D01*
X473203D01*
Y9642D01*
X473138D01*
Y9610D01*
X473106D01*
Y9578D01*
X473041D01*
Y9546D01*
X473009D01*
Y9513D01*
X472977D01*
Y9481D01*
X472912D01*
Y9449D01*
X472880D01*
Y9417D01*
X472816D01*
Y9384D01*
X472783D01*
Y9352D01*
X472751D01*
Y9320D01*
X472686D01*
Y9287D01*
X472654D01*
Y9255D01*
X472622D01*
Y9223D01*
X472557D01*
Y9191D01*
X472525D01*
Y9159D01*
X472493D01*
Y9126D01*
X472461D01*
Y9094D01*
X472396D01*
Y9062D01*
X472364D01*
Y9029D01*
X472332D01*
Y8997D01*
X472299D01*
Y8965D01*
X472235D01*
Y8933D01*
X472202D01*
Y8900D01*
X472170D01*
Y8868D01*
X472138D01*
Y8836D01*
X472106D01*
Y8804D01*
X472041D01*
Y8771D01*
X472009D01*
Y8739D01*
X471977D01*
Y8707D01*
X471944D01*
Y8675D01*
X471912D01*
Y8642D01*
X471880D01*
Y8610D01*
X471848D01*
Y8578D01*
X471815D01*
Y8546D01*
X471751D01*
Y8513D01*
X471719D01*
Y8481D01*
X471686D01*
Y8449D01*
X471654D01*
Y8416D01*
X471622D01*
Y8384D01*
X471590D01*
Y8352D01*
X471557D01*
Y8320D01*
X471525D01*
Y8287D01*
X471493D01*
Y8255D01*
X471460D01*
Y8223D01*
X471428D01*
Y8191D01*
X471396D01*
Y8158D01*
X471364D01*
Y8126D01*
X471332D01*
Y8094D01*
X471299D01*
Y8062D01*
X471267D01*
Y8029D01*
X471235D01*
Y7997D01*
X471202D01*
Y7965D01*
X471170D01*
Y7932D01*
X471138D01*
Y7900D01*
X471106D01*
Y7868D01*
X471073D01*
Y7836D01*
X471041D01*
Y7803D01*
X471009D01*
Y7771D01*
X470977D01*
Y7739D01*
Y7707D01*
X470944D01*
Y7674D01*
X470912D01*
Y7642D01*
X470880D01*
Y7610D01*
X470848D01*
Y7578D01*
X470815D01*
Y7545D01*
X470783D01*
Y7513D01*
X470751D01*
Y7481D01*
X470718D01*
Y7449D01*
Y7416D01*
X470686D01*
Y7384D01*
X470654D01*
Y7352D01*
X470622D01*
Y7320D01*
X470589D01*
Y7287D01*
X470557D01*
Y7255D01*
Y7223D01*
X470525D01*
Y7191D01*
X470493D01*
Y7158D01*
X470460D01*
Y7126D01*
X470977D01*
Y7158D01*
X471009D01*
Y7191D01*
X471041D01*
Y7223D01*
Y7255D01*
X471073D01*
Y7287D01*
X471106D01*
Y7320D01*
X471138D01*
Y7352D01*
X471170D01*
Y7384D01*
X471202D01*
Y7416D01*
X471235D01*
Y7449D01*
X471267D01*
Y7481D01*
X471299D01*
Y7513D01*
Y7545D01*
X471332D01*
Y7578D01*
X471364D01*
Y7610D01*
X471396D01*
Y7642D01*
X471428D01*
Y7674D01*
X471460D01*
Y7707D01*
X471493D01*
Y7739D01*
X471525D01*
Y7771D01*
X471557D01*
Y7803D01*
X471590D01*
Y7836D01*
X471622D01*
Y7868D01*
X471654D01*
Y7900D01*
X471686D01*
Y7932D01*
X471719D01*
Y7965D01*
X471751D01*
Y7997D01*
X471783D01*
Y8029D01*
X471815D01*
Y8062D01*
X471848D01*
Y8094D01*
X471880D01*
Y8126D01*
X471912D01*
Y8158D01*
X471944D01*
Y8191D01*
X472009D01*
Y8223D01*
X472041D01*
Y8255D01*
X472074D01*
Y8287D01*
X472106D01*
Y8320D01*
X472138D01*
Y8352D01*
X472170D01*
Y8384D01*
X472202D01*
Y8416D01*
X472235D01*
Y8449D01*
X472267D01*
Y8481D01*
X472332D01*
Y8513D01*
X472364D01*
Y8546D01*
X472396D01*
Y8578D01*
X472428D01*
Y8610D01*
X472461D01*
Y8642D01*
X472525D01*
Y8675D01*
X472557D01*
Y8707D01*
X472590D01*
Y8739D01*
X472622D01*
Y8771D01*
X472686D01*
Y8804D01*
X472719D01*
Y8836D01*
X472751D01*
Y8868D01*
X472783D01*
Y8900D01*
X472848D01*
Y8933D01*
X472880D01*
Y8965D01*
X472912D01*
Y8997D01*
X472977D01*
Y9029D01*
X473009D01*
Y9062D01*
X473041D01*
Y9094D01*
X473106D01*
Y9126D01*
X473138D01*
Y9159D01*
X473170D01*
Y9191D01*
X473235D01*
Y9223D01*
X473267D01*
Y9255D01*
X473332D01*
Y9287D01*
X473364D01*
Y9320D01*
X473428D01*
Y9352D01*
X473461D01*
Y9384D01*
X473525D01*
Y9417D01*
X473558D01*
Y9449D01*
X473622D01*
Y9481D01*
X473654D01*
Y9513D01*
X473719D01*
Y9546D01*
X473751D01*
Y9578D01*
X473816D01*
Y9610D01*
X473880D01*
Y9642D01*
X473912D01*
Y9675D01*
X473977D01*
Y9707D01*
X474041D01*
Y9739D01*
X474074D01*
Y9771D01*
X474138D01*
Y9804D01*
X474203D01*
Y9836D01*
X474235D01*
Y9868D01*
X474299D01*
Y9900D01*
X474364D01*
Y9933D01*
X474429D01*
Y9965D01*
X474493D01*
Y9997D01*
X474558D01*
Y10029D01*
X474622D01*
Y10062D01*
X474654D01*
Y10094D01*
X474719D01*
Y10126D01*
X474784D01*
Y10159D01*
X474848D01*
Y10191D01*
X474913D01*
Y10223D01*
X475009D01*
Y10255D01*
X475074D01*
Y10288D01*
X475138D01*
Y10320D01*
X475203D01*
Y10352D01*
X475267D01*
Y10384D01*
X475332D01*
Y10417D01*
X475429D01*
Y10449D01*
X475493D01*
Y10481D01*
X475558D01*
Y10514D01*
X475655D01*
Y10546D01*
X475719D01*
Y10578D01*
X475816D01*
Y10610D01*
X475913D01*
Y10643D01*
X475977D01*
Y10675D01*
X476074D01*
Y10707D01*
X476171D01*
Y10739D01*
X476267D01*
Y10772D01*
X476332D01*
Y10804D01*
X476461D01*
Y10836D01*
X476558D01*
Y10868D01*
X476655D01*
Y10901D01*
X476751D01*
Y10933D01*
X476881D01*
Y10965D01*
X476977D01*
Y10997D01*
X477106D01*
Y11030D01*
X477235D01*
Y11062D01*
X477364D01*
Y11094D01*
X477493D01*
Y11126D01*
X477655D01*
Y11159D01*
X477816D01*
Y11191D01*
X477945D01*
Y11223D01*
X478171D01*
Y11255D01*
X478365D01*
Y11288D01*
X478590D01*
Y11320D01*
X478849D01*
Y11352D01*
X479203D01*
Y11384D01*
X479784D01*
Y11417D01*
X480591D01*
Y11384D01*
X480623D01*
Y11417D01*
X480655D01*
Y11384D01*
X481171D01*
Y11352D01*
X481526D01*
Y11320D01*
X481816D01*
Y11288D01*
X482010D01*
Y11255D01*
X482204D01*
Y11223D01*
X482397D01*
Y11191D01*
X482559D01*
Y11159D01*
X482720D01*
Y11126D01*
X482881D01*
Y11094D01*
X483010D01*
Y11062D01*
X483139D01*
Y11030D01*
X483268D01*
Y10997D01*
X483397D01*
Y10965D01*
X483494D01*
Y10933D01*
X483623D01*
Y10901D01*
X483720D01*
Y10868D01*
X483817D01*
Y10836D01*
X483914D01*
Y10804D01*
X484010D01*
Y10772D01*
X484107D01*
Y10739D01*
X484204D01*
Y10707D01*
X484301D01*
Y10675D01*
X484398D01*
Y10643D01*
X484462D01*
Y10610D01*
X484559D01*
Y10578D01*
X484623D01*
Y10546D01*
X484720D01*
Y10514D01*
X484785D01*
Y10481D01*
X484881D01*
Y10449D01*
X484946D01*
Y10417D01*
X485010D01*
Y10384D01*
X485107D01*
Y10352D01*
X485172D01*
Y10320D01*
X485236D01*
Y10288D01*
X485301D01*
Y10255D01*
X485365D01*
Y10223D01*
X485462D01*
Y10191D01*
X485527D01*
Y10159D01*
X485559D01*
Y10126D01*
X485623D01*
Y10094D01*
X485688D01*
Y10062D01*
X485752D01*
Y10029D01*
X485817D01*
Y9997D01*
X485882D01*
Y9965D01*
X485946D01*
Y9933D01*
X486011D01*
Y9900D01*
X486075D01*
Y9868D01*
X486107D01*
Y9836D01*
X486172D01*
Y9804D01*
X486236D01*
Y9771D01*
X486301D01*
Y9739D01*
X486333D01*
Y9707D01*
X486398D01*
Y9675D01*
X486462D01*
Y9642D01*
X486494D01*
Y9610D01*
X486559D01*
Y9578D01*
X486623D01*
Y9546D01*
X486656D01*
Y9513D01*
X486720D01*
Y9481D01*
X486753D01*
Y9449D01*
X486817D01*
Y9417D01*
X486849D01*
Y9384D01*
X486914D01*
Y9352D01*
X486946D01*
Y9320D01*
X487011D01*
Y9287D01*
X487043D01*
Y9255D01*
X487108D01*
Y9223D01*
X487140D01*
Y9191D01*
X487172D01*
Y9159D01*
X487236D01*
Y9126D01*
X487269D01*
Y9094D01*
X487333D01*
Y9062D01*
X487366D01*
Y9029D01*
X487398D01*
Y8997D01*
X487462D01*
Y8965D01*
X487495D01*
Y8933D01*
X487527D01*
Y8900D01*
X487591D01*
Y8868D01*
X487624D01*
Y8836D01*
X487656D01*
Y8804D01*
X487688D01*
Y8771D01*
X487753D01*
Y8739D01*
X487785D01*
Y8707D01*
X487817D01*
Y8675D01*
X487850D01*
Y8642D01*
X487914D01*
Y8610D01*
X487946D01*
Y8578D01*
X487979D01*
Y8546D01*
X488011D01*
Y8513D01*
X488043D01*
Y8481D01*
X488075D01*
Y8449D01*
X488140D01*
Y8416D01*
X488172D01*
Y8384D01*
X488204D01*
Y8352D01*
X488237D01*
Y8320D01*
X488269D01*
Y8287D01*
X488301D01*
Y8255D01*
X488333D01*
Y8223D01*
X488366D01*
Y8191D01*
X488398D01*
Y8158D01*
X488462D01*
Y8126D01*
X488495D01*
Y8094D01*
X488527D01*
Y8062D01*
X488559D01*
Y8029D01*
X488591D01*
Y7997D01*
X488624D01*
Y7965D01*
X488656D01*
Y7932D01*
X488688D01*
Y7900D01*
X488721D01*
Y7868D01*
X488753D01*
Y7836D01*
X488785D01*
Y7803D01*
X488817D01*
Y7771D01*
X488850D01*
Y7739D01*
X488882D01*
Y7707D01*
X488914D01*
Y7674D01*
X488946D01*
Y7642D01*
X488979D01*
Y7610D01*
X489011D01*
Y7578D01*
Y7545D01*
X489043D01*
Y7513D01*
X489076D01*
Y7481D01*
X489108D01*
Y7449D01*
X489140D01*
Y7416D01*
X489172D01*
Y7384D01*
X489205D01*
Y7352D01*
X489237D01*
Y7320D01*
X489269D01*
Y7287D01*
X489301D01*
Y7255D01*
Y7223D01*
X489333D01*
Y7191D01*
X489366D01*
Y7158D01*
X489398D01*
Y7126D01*
X489430D01*
Y7094D01*
X489463D01*
Y7062D01*
X489495D01*
Y7029D01*
Y6997D01*
X489527D01*
Y6965D01*
X489559D01*
Y6932D01*
X489592D01*
Y6900D01*
X489624D01*
Y6868D01*
Y6836D01*
X489656D01*
Y6803D01*
X489688D01*
Y6771D01*
X489721D01*
Y6739D01*
X489753D01*
Y6707D01*
Y6674D01*
X489785D01*
Y6642D01*
X489817D01*
Y6610D01*
X489850D01*
Y6577D01*
Y6545D01*
X489882D01*
Y6513D01*
X489914D01*
Y6481D01*
X489947D01*
Y6448D01*
Y6416D01*
X489979D01*
Y6384D01*
X490011D01*
Y6352D01*
Y6319D01*
X490043D01*
Y6287D01*
X490076D01*
Y6255D01*
X490108D01*
Y6223D01*
Y6190D01*
X490140D01*
Y6158D01*
X490172D01*
Y6126D01*
Y6094D01*
X490205D01*
Y6061D01*
X490237D01*
Y6029D01*
Y5997D01*
X490269D01*
Y5965D01*
X490301D01*
Y5932D01*
Y5900D01*
X490334D01*
Y5868D01*
X490366D01*
Y5835D01*
Y5803D01*
X490398D01*
Y5771D01*
X490430D01*
Y5739D01*
Y5706D01*
X490463D01*
Y5674D01*
Y5642D01*
X490495D01*
Y5610D01*
X490527D01*
Y5577D01*
Y5545D01*
X490559D01*
Y5513D01*
Y5481D01*
X490592D01*
Y5448D01*
X490624D01*
Y5416D01*
Y5384D01*
X490656D01*
Y5352D01*
Y5319D01*
X490689D01*
Y5287D01*
Y5255D01*
X490721D01*
Y5223D01*
X490753D01*
Y5190D01*
Y5158D01*
X490785D01*
Y5126D01*
Y5094D01*
X490818D01*
Y5061D01*
Y5029D01*
X490850D01*
Y4997D01*
Y4964D01*
X490882D01*
Y4932D01*
Y4900D01*
X490914D01*
Y4868D01*
X490947D01*
Y4835D01*
Y4803D01*
X490979D01*
Y4771D01*
Y4739D01*
X491011D01*
Y4706D01*
Y4674D01*
X491043D01*
Y4642D01*
Y4610D01*
X491076D01*
Y4577D01*
Y4545D01*
Y4513D01*
X491108D01*
Y4481D01*
Y4448D01*
X491140D01*
Y4416D01*
Y4384D01*
X491173D01*
Y4352D01*
Y4319D01*
X491205D01*
Y4287D01*
Y4255D01*
X491237D01*
Y4222D01*
Y4190D01*
X491269D01*
Y4158D01*
Y4126D01*
Y4093D01*
X491301D01*
Y4061D01*
Y4029D01*
X491334D01*
Y3997D01*
Y3964D01*
X491366D01*
Y3932D01*
Y3900D01*
Y3867D01*
X491398D01*
Y3835D01*
Y3803D01*
X491431D01*
Y3771D01*
Y3739D01*
Y3706D01*
X491463D01*
Y3674D01*
Y3642D01*
X491495D01*
Y3609D01*
Y3577D01*
Y3545D01*
X491527D01*
Y3513D01*
Y3480D01*
Y3448D01*
X491560D01*
Y3416D01*
Y3384D01*
Y3351D01*
X491592D01*
Y3319D01*
Y3287D01*
X491624D01*
Y3255D01*
Y3222D01*
Y3190D01*
X491656D01*
Y3158D01*
Y3125D01*
Y3093D01*
X491689D01*
Y3061D01*
Y3029D01*
Y2997D01*
Y2964D01*
X491721D01*
Y2932D01*
Y2900D01*
Y2867D01*
X491753D01*
Y2835D01*
Y2803D01*
Y2771D01*
X491785D01*
Y2738D01*
Y2706D01*
Y2674D01*
Y2642D01*
X491818D01*
Y2609D01*
Y2577D01*
Y2545D01*
X491850D01*
Y2513D01*
Y2480D01*
Y2448D01*
Y2416D01*
X491882D01*
Y2383D01*
Y2351D01*
Y2319D01*
Y2287D01*
X491915D01*
Y2254D01*
Y2222D01*
Y2190D01*
Y2158D01*
X491947D01*
Y2125D01*
Y2093D01*
Y2061D01*
Y2029D01*
X491979D01*
Y1996D01*
Y1964D01*
Y1932D01*
Y1900D01*
Y1867D01*
X492011D01*
Y1835D01*
Y1803D01*
Y1770D01*
Y1738D01*
X492043D01*
Y1706D01*
Y1674D01*
Y1641D01*
Y1609D01*
Y1577D01*
Y1545D01*
X492076D01*
Y1512D01*
Y1480D01*
Y1448D01*
Y1416D01*
Y1383D01*
X492108D01*
Y1351D01*
Y1319D01*
Y1287D01*
Y1254D01*
Y1222D01*
Y1190D01*
X492140D01*
Y1158D01*
Y1125D01*
Y1093D01*
Y1061D01*
Y1029D01*
Y996D01*
Y964D01*
X492173D01*
Y932D01*
Y900D01*
Y867D01*
Y835D01*
Y803D01*
Y770D01*
Y738D01*
Y706D01*
Y674D01*
X492205D01*
Y641D01*
Y609D01*
Y577D01*
Y545D01*
Y512D01*
Y480D01*
Y448D01*
Y416D01*
Y383D01*
X492237D01*
Y351D01*
Y319D01*
Y286D01*
Y254D01*
Y222D01*
Y190D01*
Y157D01*
Y125D01*
Y93D01*
Y61D01*
Y28D01*
Y-4D01*
Y-36D01*
Y-68D01*
Y-101D01*
Y-133D01*
Y-165D01*
X492269D01*
Y-197D01*
Y-230D01*
Y-262D01*
Y-294D01*
Y-326D01*
Y-359D01*
Y-391D01*
Y-423D01*
Y-455D01*
Y-488D01*
Y-520D01*
X492657D01*
Y-488D01*
Y-455D01*
Y-423D01*
Y-391D01*
Y-359D01*
Y-326D01*
Y-294D01*
Y-262D01*
Y-230D01*
Y-197D01*
Y-165D01*
Y-133D01*
X492624D01*
Y-101D01*
X492657D01*
Y-68D01*
Y-36D01*
Y-4D01*
X492624D01*
Y28D01*
Y61D01*
Y93D01*
Y125D01*
Y157D01*
Y190D01*
Y222D01*
Y254D01*
Y286D01*
Y319D01*
Y351D01*
Y383D01*
Y416D01*
Y448D01*
X492592D01*
Y480D01*
Y512D01*
Y545D01*
Y577D01*
Y609D01*
Y641D01*
Y674D01*
Y706D01*
Y738D01*
Y770D01*
X492560D01*
Y803D01*
Y835D01*
Y867D01*
Y900D01*
Y932D01*
Y964D01*
Y996D01*
Y1029D01*
X492527D01*
Y1061D01*
Y1093D01*
Y1125D01*
Y1158D01*
Y1190D01*
Y1222D01*
Y1254D01*
X492495D01*
Y1287D01*
Y1319D01*
Y1351D01*
Y1383D01*
Y1416D01*
Y1448D01*
X492463D01*
Y1480D01*
Y1512D01*
Y1545D01*
Y1577D01*
Y1609D01*
X492431D01*
Y1641D01*
Y1674D01*
Y1706D01*
Y1738D01*
Y1770D01*
X492398D01*
Y1803D01*
Y1835D01*
Y1867D01*
Y1900D01*
Y1932D01*
X492366D01*
Y1964D01*
Y1996D01*
Y2029D01*
Y2061D01*
Y2093D01*
X492334D01*
Y2125D01*
Y2158D01*
Y2190D01*
Y2222D01*
X492302D01*
Y2254D01*
Y2287D01*
Y2319D01*
Y2351D01*
X492269D01*
Y2383D01*
Y2416D01*
Y2448D01*
Y2480D01*
X492237D01*
Y2513D01*
Y2545D01*
Y2577D01*
Y2609D01*
X492205D01*
Y2642D01*
Y2674D01*
Y2706D01*
X492173D01*
Y2738D01*
Y2771D01*
Y2803D01*
Y2835D01*
X492140D01*
Y2867D01*
Y2900D01*
Y2932D01*
X492108D01*
Y2964D01*
Y2997D01*
Y3029D01*
Y3061D01*
X492076D01*
Y3093D01*
Y3125D01*
Y3158D01*
X492043D01*
Y3190D01*
Y3222D01*
Y3255D01*
X492011D01*
Y3287D01*
Y3319D01*
Y3351D01*
X491979D01*
Y3384D01*
Y3416D01*
Y3448D01*
X491947D01*
Y3480D01*
Y3513D01*
Y3545D01*
X491915D01*
Y3577D01*
Y3609D01*
X491882D01*
Y3642D01*
Y3674D01*
Y3706D01*
X491850D01*
Y3739D01*
Y3771D01*
Y3803D01*
X491818D01*
Y3835D01*
Y3867D01*
X491785D01*
Y3900D01*
Y3932D01*
Y3964D01*
X491753D01*
Y3997D01*
Y4029D01*
X491721D01*
Y4061D01*
Y4093D01*
Y4126D01*
X491689D01*
Y4158D01*
Y4190D01*
X491656D01*
Y4222D01*
Y4255D01*
X491624D01*
Y4287D01*
Y4319D01*
Y4352D01*
X491592D01*
Y4384D01*
Y4416D01*
X491560D01*
Y4448D01*
Y4481D01*
X491527D01*
Y4513D01*
Y4545D01*
X491495D01*
Y4577D01*
Y4610D01*
Y4642D01*
X491463D01*
Y4674D01*
Y4706D01*
X491431D01*
Y4739D01*
Y4771D01*
X491398D01*
Y4803D01*
Y4835D01*
X491366D01*
Y4868D01*
Y4900D01*
X491334D01*
Y4932D01*
Y4964D01*
X491301D01*
Y4997D01*
Y5029D01*
X491269D01*
Y5061D01*
Y5094D01*
X491237D01*
Y5126D01*
Y5158D01*
X491205D01*
Y5190D01*
Y5223D01*
X491173D01*
Y5255D01*
X491140D01*
Y5287D01*
Y5319D01*
X491108D01*
Y5352D01*
Y5384D01*
X491076D01*
Y5416D01*
Y5448D01*
X491043D01*
Y5481D01*
Y5513D01*
X491011D01*
Y5545D01*
X490979D01*
Y5577D01*
Y5610D01*
X490947D01*
Y5642D01*
Y5674D01*
X490914D01*
Y5706D01*
X490882D01*
Y5739D01*
Y5771D01*
X490850D01*
Y5803D01*
Y5835D01*
X490818D01*
Y5868D01*
X490785D01*
Y5900D01*
Y5932D01*
X490753D01*
Y5965D01*
Y5997D01*
X490721D01*
Y6029D01*
X490689D01*
Y6061D01*
Y6094D01*
X490656D01*
Y6126D01*
X490624D01*
Y6158D01*
Y6190D01*
X490592D01*
Y6223D01*
X490559D01*
Y6255D01*
Y6287D01*
X490527D01*
Y6319D01*
X490495D01*
Y6352D01*
Y6384D01*
X490463D01*
Y6416D01*
X490430D01*
Y6448D01*
Y6481D01*
X490398D01*
Y6513D01*
X490366D01*
Y6545D01*
X490334D01*
Y6577D01*
Y6610D01*
X490301D01*
Y6642D01*
X490269D01*
Y6674D01*
Y6707D01*
X490237D01*
Y6739D01*
X490205D01*
Y6771D01*
X490172D01*
Y6803D01*
Y6836D01*
X490140D01*
Y6868D01*
X490108D01*
Y6900D01*
X490076D01*
Y6932D01*
X490043D01*
Y6965D01*
Y6997D01*
X490011D01*
Y7029D01*
X489979D01*
Y7062D01*
X489947D01*
Y7094D01*
Y7126D01*
X489914D01*
Y7158D01*
X489882D01*
Y7191D01*
X489850D01*
Y7223D01*
X489817D01*
Y7255D01*
X489785D01*
Y7287D01*
Y7320D01*
X489753D01*
Y7352D01*
X489721D01*
Y7384D01*
X489688D01*
Y7416D01*
X489656D01*
Y7449D01*
X489624D01*
Y7481D01*
Y7513D01*
X489592D01*
Y7545D01*
X489559D01*
Y7578D01*
X489527D01*
Y7610D01*
X489495D01*
Y7642D01*
X489463D01*
Y7674D01*
X489430D01*
Y7707D01*
X489398D01*
Y7739D01*
X489366D01*
Y7771D01*
Y7803D01*
X489333D01*
Y7836D01*
X489301D01*
Y7868D01*
X489269D01*
Y7900D01*
X489237D01*
Y7932D01*
X489205D01*
Y7965D01*
X489172D01*
Y7997D01*
X489140D01*
Y8029D01*
X489108D01*
Y8062D01*
X489076D01*
Y8094D01*
X489043D01*
Y8126D01*
X489011D01*
Y8158D01*
X488979D01*
Y8191D01*
X488946D01*
Y8223D01*
X488914D01*
Y8255D01*
X488882D01*
Y8287D01*
X488850D01*
Y8320D01*
X488817D01*
Y8352D01*
X488785D01*
Y8384D01*
X488753D01*
Y8416D01*
X488721D01*
Y8449D01*
X488688D01*
Y8481D01*
X488624D01*
Y8513D01*
X488591D01*
Y8546D01*
X488559D01*
Y8578D01*
X488527D01*
Y8610D01*
X488495D01*
Y8642D01*
X488462D01*
Y8675D01*
X488430D01*
Y8707D01*
X488398D01*
Y8739D01*
X488366D01*
Y8771D01*
X488301D01*
Y8804D01*
X488269D01*
Y8836D01*
X488237D01*
Y8868D01*
X488204D01*
Y8900D01*
X488172D01*
Y8933D01*
X488108D01*
Y8965D01*
X488075D01*
Y8997D01*
X488043D01*
Y9029D01*
X488011D01*
Y9062D01*
X487979D01*
Y9094D01*
X487914D01*
Y9126D01*
X487882D01*
Y9159D01*
X487850D01*
Y9191D01*
X487785D01*
Y9223D01*
X487753D01*
Y9255D01*
X487720D01*
Y9287D01*
X487688D01*
Y9320D01*
X487624D01*
Y9352D01*
X487591D01*
Y9384D01*
X487527D01*
Y9417D01*
X487495D01*
Y9449D01*
X487462D01*
Y9481D01*
X487398D01*
Y9513D01*
X487366D01*
Y9546D01*
X487333D01*
Y9578D01*
X487269D01*
Y9610D01*
X487236D01*
Y9642D01*
X487172D01*
Y9675D01*
X487140D01*
Y9707D01*
X487075D01*
Y9739D01*
X487043D01*
Y9771D01*
X486978D01*
Y9804D01*
X486946D01*
Y9836D01*
X486882D01*
Y9868D01*
X486817D01*
Y9900D01*
X486785D01*
Y9933D01*
X486720D01*
Y9965D01*
X486688D01*
Y9997D01*
X486623D01*
Y10029D01*
X486559D01*
Y10062D01*
X486527D01*
Y10094D01*
X486462D01*
Y10126D01*
X486398D01*
Y10159D01*
X486333D01*
Y10191D01*
X486301D01*
Y10223D01*
X486236D01*
Y10255D01*
X486172D01*
Y10288D01*
X486107D01*
Y10320D01*
X486043D01*
Y10352D01*
X486011D01*
Y10384D01*
X485914D01*
Y10417D01*
X485882D01*
Y10449D01*
X485817D01*
Y10481D01*
X485720D01*
Y10514D01*
X485656D01*
Y10546D01*
X485623D01*
Y10578D01*
X485559D01*
Y10610D01*
X485462D01*
Y10643D01*
X485398D01*
Y10675D01*
X485333D01*
Y10707D01*
X485269D01*
Y10739D01*
X485204D01*
Y10772D01*
X485107D01*
Y10804D01*
X485043D01*
Y10836D01*
X484978D01*
Y10868D01*
X484881D01*
Y10901D01*
X484817D01*
Y10933D01*
X484720D01*
Y10965D01*
X484623D01*
Y10997D01*
X484559D01*
Y11030D01*
X484462D01*
Y11062D01*
X484365D01*
Y11094D01*
X484268D01*
Y11126D01*
X484204D01*
Y11159D01*
X484107D01*
Y11191D01*
X484010D01*
Y11223D01*
X483881D01*
Y11255D01*
X483784D01*
Y11288D01*
X483688D01*
Y11320D01*
X483559D01*
Y11352D01*
X483462D01*
Y11384D01*
X483333D01*
Y11417D01*
X483204D01*
Y11449D01*
X483075D01*
Y11481D01*
X482946D01*
Y11514D01*
X482784D01*
Y11546D01*
X482623D01*
Y11578D01*
X482462D01*
Y11610D01*
X482268D01*
Y11643D01*
X482075D01*
Y11675D01*
X481816D01*
Y11707D01*
X481558D01*
Y11739D01*
X481268D01*
Y11772D01*
X480784D01*
Y11804D01*
D02*
G37*
G36*
X476267Y-1004D02*
X476203D01*
Y-1036D01*
X476171D01*
Y-1004D01*
X472299D01*
Y-1036D01*
X472202D01*
Y-1068D01*
X472106D01*
Y-1101D01*
X472041D01*
Y-1133D01*
X472009D01*
Y-1165D01*
X471977D01*
Y-1198D01*
X471944D01*
Y-1230D01*
X471912D01*
Y-1262D01*
X471880D01*
Y-1294D01*
X471848D01*
Y-1327D01*
X471815D01*
Y-1359D01*
X471783D01*
Y-1391D01*
X471751D01*
Y-1423D01*
X471719D01*
Y-1456D01*
X471686D01*
Y-1488D01*
X471654D01*
Y-1520D01*
X471622D01*
Y-1552D01*
X471590D01*
Y-1585D01*
X471557D01*
Y-1617D01*
X471525D01*
Y-1649D01*
X471493D01*
Y-1681D01*
X471460D01*
Y-1714D01*
X471428D01*
Y-1746D01*
X471396D01*
Y-1778D01*
X471364D01*
Y-1811D01*
X471332D01*
Y-1843D01*
X471299D01*
Y-1875D01*
X471267D01*
Y-1907D01*
X471235D01*
Y-1940D01*
X471202D01*
Y-1972D01*
X471170D01*
Y-2004D01*
X471138D01*
Y-2036D01*
Y-2069D01*
X471106D01*
Y-2101D01*
Y-2133D01*
Y-2165D01*
Y-2198D01*
X471073D01*
Y-2230D01*
Y-2262D01*
Y-2294D01*
Y-2327D01*
Y-2359D01*
Y-2391D01*
Y-2424D01*
Y-2456D01*
Y-2488D01*
Y-2520D01*
Y-2553D01*
Y-2585D01*
Y-2617D01*
Y-2649D01*
Y-2682D01*
Y-2714D01*
Y-2746D01*
Y-2778D01*
Y-2811D01*
Y-2843D01*
Y-2875D01*
Y-2907D01*
Y-2940D01*
Y-2972D01*
Y-3004D01*
Y-3036D01*
Y-3069D01*
Y-3101D01*
Y-3133D01*
Y-3165D01*
Y-3198D01*
Y-3230D01*
Y-3262D01*
Y-3295D01*
Y-3327D01*
Y-3359D01*
Y-3391D01*
Y-3424D01*
Y-3456D01*
Y-3488D01*
Y-3520D01*
Y-3553D01*
Y-3585D01*
Y-3617D01*
Y-3650D01*
Y-3682D01*
Y-3714D01*
Y-3746D01*
Y-3779D01*
Y-3811D01*
Y-3843D01*
Y-3875D01*
Y-3907D01*
Y-3940D01*
Y-3972D01*
Y-4004D01*
Y-4037D01*
Y-4069D01*
Y-4101D01*
Y-4133D01*
Y-4166D01*
Y-4198D01*
Y-4230D01*
Y-4262D01*
Y-4295D01*
Y-4327D01*
Y-4359D01*
Y-4391D01*
Y-4424D01*
Y-4456D01*
Y-4488D01*
Y-4521D01*
Y-4553D01*
Y-4585D01*
Y-4617D01*
Y-4650D01*
Y-4682D01*
Y-4714D01*
Y-4746D01*
Y-4779D01*
Y-4811D01*
Y-4843D01*
Y-4875D01*
Y-4908D01*
Y-4940D01*
Y-4972D01*
Y-5004D01*
Y-5037D01*
Y-5069D01*
Y-5101D01*
Y-5133D01*
Y-5166D01*
Y-5198D01*
Y-5230D01*
Y-5263D01*
Y-5295D01*
Y-5327D01*
Y-5359D01*
Y-5392D01*
Y-5424D01*
Y-5456D01*
Y-5488D01*
Y-5521D01*
Y-5553D01*
Y-5585D01*
Y-5617D01*
Y-5650D01*
Y-5682D01*
Y-5714D01*
Y-5746D01*
Y-5779D01*
Y-5811D01*
Y-5843D01*
Y-5875D01*
Y-5908D01*
Y-5940D01*
Y-5972D01*
Y-6005D01*
Y-6037D01*
Y-6069D01*
Y-6101D01*
Y-6134D01*
Y-6166D01*
Y-6198D01*
Y-6230D01*
Y-6263D01*
Y-6295D01*
Y-6327D01*
Y-6359D01*
Y-6392D01*
Y-6424D01*
Y-6456D01*
Y-6488D01*
Y-6521D01*
Y-6553D01*
Y-6585D01*
Y-6617D01*
Y-6650D01*
Y-6682D01*
Y-6714D01*
Y-6747D01*
Y-6779D01*
Y-6811D01*
Y-6843D01*
Y-6876D01*
X471106D01*
Y-6908D01*
Y-6940D01*
Y-6972D01*
X471138D01*
Y-7005D01*
Y-7037D01*
X471170D01*
Y-7069D01*
X471202D01*
Y-7102D01*
X471235D01*
Y-7134D01*
X471267D01*
Y-7166D01*
X471299D01*
Y-7198D01*
X471332D01*
Y-7231D01*
X471364D01*
Y-7263D01*
X471396D01*
Y-7295D01*
X471428D01*
Y-7327D01*
X471460D01*
Y-7360D01*
X471493D01*
Y-7392D01*
X471525D01*
Y-7424D01*
X471557D01*
Y-7456D01*
X471590D01*
Y-7489D01*
X471622D01*
Y-7521D01*
X471654D01*
Y-7553D01*
X471686D01*
Y-7585D01*
X471719D01*
Y-7618D01*
X471751D01*
Y-7650D01*
X471783D01*
Y-7682D01*
X471815D01*
Y-7714D01*
X471848D01*
Y-7747D01*
X471880D01*
Y-7779D01*
X471912D01*
Y-7811D01*
X471944D01*
Y-7843D01*
X471977D01*
Y-7876D01*
X472009D01*
Y-7908D01*
X472041D01*
Y-7940D01*
X472074D01*
Y-7972D01*
X472138D01*
Y-8005D01*
X472235D01*
Y-8037D01*
X476332D01*
Y-8005D01*
X476364D01*
Y-7972D01*
X476397D01*
Y-7940D01*
X476429D01*
Y-7908D01*
Y-7876D01*
Y-7843D01*
Y-7811D01*
Y-7779D01*
Y-7747D01*
Y-7714D01*
Y-7682D01*
Y-7650D01*
Y-7618D01*
Y-7585D01*
Y-7553D01*
Y-7521D01*
Y-7489D01*
Y-7456D01*
Y-7424D01*
Y-7392D01*
Y-7360D01*
Y-7327D01*
Y-7295D01*
Y-7263D01*
Y-7231D01*
Y-7198D01*
Y-7166D01*
Y-7134D01*
Y-7102D01*
Y-7069D01*
Y-7037D01*
Y-7005D01*
Y-6972D01*
Y-6940D01*
Y-6908D01*
Y-6876D01*
Y-6843D01*
Y-6811D01*
Y-6779D01*
Y-6747D01*
Y-6714D01*
Y-6682D01*
Y-6650D01*
Y-6617D01*
Y-6585D01*
Y-6553D01*
Y-6521D01*
Y-6488D01*
Y-6456D01*
Y-6424D01*
X476397D01*
Y-6392D01*
X476364D01*
Y-6359D01*
X476300D01*
Y-6327D01*
X472944D01*
Y-6295D01*
X472880D01*
Y-6263D01*
Y-6230D01*
X472848D01*
Y-6198D01*
Y-6166D01*
Y-6134D01*
Y-6101D01*
Y-6069D01*
Y-6037D01*
Y-6005D01*
Y-5972D01*
Y-5940D01*
Y-5908D01*
Y-5875D01*
Y-5843D01*
Y-5811D01*
Y-5779D01*
Y-5746D01*
Y-5714D01*
Y-5682D01*
Y-5650D01*
Y-5617D01*
Y-5585D01*
Y-5553D01*
Y-5521D01*
Y-5488D01*
Y-5456D01*
Y-5424D01*
Y-5392D01*
Y-5359D01*
Y-5327D01*
Y-5295D01*
Y-5263D01*
Y-5230D01*
Y-5198D01*
Y-5166D01*
Y-5133D01*
Y-5101D01*
Y-5069D01*
Y-5037D01*
Y-5004D01*
Y-4972D01*
Y-4940D01*
Y-4908D01*
Y-4875D01*
Y-4843D01*
Y-4811D01*
Y-4779D01*
Y-4746D01*
Y-4714D01*
Y-4682D01*
Y-4650D01*
Y-4617D01*
Y-4585D01*
Y-4553D01*
Y-4521D01*
Y-4488D01*
Y-4456D01*
Y-4424D01*
Y-4391D01*
Y-4359D01*
Y-4327D01*
Y-4295D01*
Y-4262D01*
Y-4230D01*
Y-4198D01*
Y-4166D01*
Y-4133D01*
Y-4101D01*
Y-4069D01*
Y-4037D01*
Y-4004D01*
Y-3972D01*
Y-3940D01*
Y-3907D01*
Y-3875D01*
Y-3843D01*
Y-3811D01*
Y-3779D01*
Y-3746D01*
Y-3714D01*
Y-3682D01*
Y-3650D01*
Y-3617D01*
Y-3585D01*
Y-3553D01*
Y-3520D01*
Y-3488D01*
Y-3456D01*
Y-3424D01*
Y-3391D01*
Y-3359D01*
Y-3327D01*
Y-3295D01*
Y-3262D01*
Y-3230D01*
Y-3198D01*
Y-3165D01*
Y-3133D01*
Y-3101D01*
Y-3069D01*
Y-3036D01*
Y-3004D01*
Y-2972D01*
Y-2940D01*
Y-2907D01*
Y-2875D01*
Y-2843D01*
Y-2811D01*
X472880D01*
Y-2778D01*
X472912D01*
Y-2746D01*
X476106D01*
Y-2714D01*
X476138D01*
Y-2746D01*
X476267D01*
Y-2714D01*
X476364D01*
Y-2682D01*
X476397D01*
Y-2649D01*
X476429D01*
Y-2617D01*
Y-2585D01*
Y-2553D01*
Y-2520D01*
Y-2488D01*
Y-2456D01*
Y-2424D01*
Y-2391D01*
Y-2359D01*
Y-2327D01*
Y-2294D01*
Y-2262D01*
Y-2230D01*
Y-2198D01*
Y-2165D01*
Y-2133D01*
Y-2101D01*
Y-2069D01*
Y-2036D01*
Y-2004D01*
Y-1972D01*
Y-1940D01*
Y-1907D01*
Y-1875D01*
Y-1843D01*
Y-1811D01*
Y-1778D01*
Y-1746D01*
Y-1714D01*
Y-1681D01*
Y-1649D01*
Y-1617D01*
Y-1585D01*
Y-1552D01*
Y-1520D01*
Y-1488D01*
Y-1456D01*
Y-1423D01*
Y-1391D01*
Y-1359D01*
Y-1327D01*
Y-1294D01*
Y-1262D01*
Y-1230D01*
Y-1198D01*
Y-1165D01*
Y-1133D01*
Y-1101D01*
X476397D01*
Y-1068D01*
X476364D01*
Y-1036D01*
X476267D01*
Y-1004D01*
D02*
G37*
G36*
X481913D02*
X481462D01*
Y-1036D01*
X481429D01*
Y-1068D01*
X481397D01*
Y-1101D01*
X481365D01*
Y-1133D01*
X481333D01*
Y-1165D01*
X481300D01*
Y-1198D01*
X481268D01*
Y-1230D01*
X481236D01*
Y-1262D01*
X481204D01*
Y-1294D01*
X481171D01*
Y-1327D01*
X481139D01*
Y-1359D01*
X481107D01*
Y-1391D01*
X481074D01*
Y-1423D01*
X481042D01*
Y-1456D01*
X481010D01*
Y-1488D01*
X480978D01*
Y-1520D01*
X480945D01*
Y-1552D01*
X480913D01*
Y-1585D01*
X480881D01*
Y-1617D01*
X480849D01*
Y-1649D01*
X480816D01*
Y-1681D01*
X480784D01*
Y-1714D01*
X480752D01*
Y-1746D01*
X480720D01*
Y-1778D01*
X480687D01*
Y-1811D01*
X480655D01*
Y-1843D01*
X480623D01*
Y-1875D01*
X480591D01*
Y-1907D01*
X480558D01*
Y-1940D01*
X480526D01*
Y-1972D01*
X480494D01*
Y-2004D01*
X480462D01*
Y-2036D01*
X480429D01*
Y-2069D01*
X480397D01*
Y-2101D01*
X480365D01*
Y-2133D01*
X480333D01*
Y-2165D01*
X480300D01*
Y-2198D01*
X480268D01*
Y-2230D01*
X480236D01*
Y-2262D01*
X480203D01*
Y-2294D01*
X480171D01*
Y-2327D01*
X480139D01*
Y-2359D01*
X480107D01*
Y-2391D01*
X480074D01*
Y-2424D01*
X480042D01*
Y-2456D01*
X480010D01*
Y-2488D01*
X479978D01*
Y-2520D01*
X479945D01*
Y-2553D01*
X479913D01*
Y-2585D01*
X481365D01*
Y-2617D01*
Y-2649D01*
Y-2682D01*
Y-2714D01*
Y-2746D01*
Y-2778D01*
Y-2811D01*
Y-2843D01*
Y-2875D01*
Y-2907D01*
Y-2940D01*
Y-2972D01*
Y-3004D01*
Y-3036D01*
Y-3069D01*
Y-3101D01*
Y-3133D01*
Y-3165D01*
Y-3198D01*
Y-3230D01*
Y-3262D01*
Y-3295D01*
Y-3327D01*
Y-3359D01*
Y-3391D01*
Y-3424D01*
Y-3456D01*
Y-3488D01*
Y-3520D01*
Y-3553D01*
Y-3585D01*
Y-3617D01*
Y-3650D01*
Y-3682D01*
Y-3714D01*
Y-3746D01*
Y-3779D01*
Y-3811D01*
Y-3843D01*
Y-3875D01*
Y-3907D01*
Y-3940D01*
Y-3972D01*
Y-4004D01*
Y-4037D01*
Y-4069D01*
Y-4101D01*
Y-4133D01*
Y-4166D01*
Y-4198D01*
Y-4230D01*
Y-4262D01*
Y-4295D01*
Y-4327D01*
Y-4359D01*
X479010D01*
Y-4327D01*
Y-4295D01*
Y-4262D01*
Y-4230D01*
Y-4198D01*
Y-4166D01*
Y-4133D01*
Y-4101D01*
Y-4069D01*
Y-4037D01*
Y-4004D01*
Y-3972D01*
Y-3940D01*
Y-3907D01*
Y-3875D01*
Y-3843D01*
Y-3811D01*
Y-3779D01*
Y-3746D01*
Y-3714D01*
Y-3682D01*
Y-3650D01*
X478977D01*
Y-3682D01*
X478945D01*
Y-3714D01*
X478913D01*
Y-3746D01*
X478881D01*
Y-3779D01*
X478849D01*
Y-3811D01*
X478816D01*
Y-3843D01*
X478784D01*
Y-3875D01*
X478752D01*
Y-3907D01*
X478719D01*
Y-3940D01*
X478687D01*
Y-3972D01*
X478655D01*
Y-4004D01*
X478623D01*
Y-4037D01*
X478590D01*
Y-4069D01*
X478558D01*
Y-4101D01*
X478526D01*
Y-4133D01*
X478494D01*
Y-4166D01*
X478461D01*
Y-4198D01*
X478429D01*
Y-4230D01*
X478397D01*
Y-4262D01*
X478365D01*
Y-4295D01*
X478332D01*
Y-4327D01*
X478300D01*
Y-4359D01*
X478268D01*
Y-4391D01*
X478235D01*
Y-4424D01*
X478203D01*
Y-4456D01*
X478171D01*
Y-4488D01*
X478139D01*
Y-4521D01*
X478106D01*
Y-4553D01*
X478074D01*
Y-4585D01*
X478042D01*
Y-4617D01*
X478010D01*
Y-4650D01*
X477977D01*
Y-4682D01*
X477945D01*
Y-4714D01*
X477913D01*
Y-4746D01*
X477881D01*
Y-4779D01*
X477848D01*
Y-4811D01*
X477816D01*
Y-4843D01*
X477784D01*
Y-4875D01*
X477752D01*
Y-4908D01*
X477719D01*
Y-4940D01*
X477687D01*
Y-4972D01*
X477655D01*
Y-5004D01*
X477623D01*
Y-5037D01*
X477590D01*
Y-5069D01*
X477558D01*
Y-5101D01*
X477526D01*
Y-5133D01*
X477493D01*
Y-5166D01*
X477429D01*
Y-5198D01*
X477397D01*
Y-5230D01*
X477364D01*
Y-5263D01*
X477332D01*
Y-5295D01*
X477300D01*
Y-5327D01*
X477268D01*
Y-5359D01*
X477235D01*
Y-5392D01*
Y-5424D01*
Y-5456D01*
Y-5488D01*
Y-5521D01*
Y-5553D01*
Y-5585D01*
Y-5617D01*
Y-5650D01*
Y-5682D01*
Y-5714D01*
Y-5746D01*
Y-5779D01*
Y-5811D01*
Y-5843D01*
Y-5875D01*
Y-5908D01*
Y-5940D01*
Y-5972D01*
Y-6005D01*
Y-6037D01*
Y-6069D01*
Y-6101D01*
Y-6134D01*
Y-6166D01*
Y-6198D01*
Y-6230D01*
Y-6263D01*
Y-6295D01*
Y-6327D01*
Y-6359D01*
Y-6392D01*
Y-6424D01*
Y-6456D01*
Y-6488D01*
Y-6521D01*
Y-6553D01*
Y-6585D01*
Y-6617D01*
Y-6650D01*
Y-6682D01*
Y-6714D01*
Y-6747D01*
Y-6779D01*
Y-6811D01*
Y-6843D01*
Y-6876D01*
Y-6908D01*
Y-6940D01*
Y-6972D01*
Y-7005D01*
Y-7037D01*
Y-7069D01*
Y-7102D01*
Y-7134D01*
Y-7166D01*
Y-7198D01*
Y-7231D01*
Y-7263D01*
Y-7295D01*
Y-7327D01*
Y-7360D01*
Y-7392D01*
Y-7424D01*
Y-7456D01*
Y-7489D01*
Y-7521D01*
Y-7553D01*
Y-7585D01*
Y-7618D01*
Y-7650D01*
Y-7682D01*
Y-7714D01*
Y-7747D01*
Y-7779D01*
Y-7811D01*
Y-7843D01*
Y-7876D01*
Y-7908D01*
Y-7940D01*
X477268D01*
Y-7972D01*
X477300D01*
Y-8005D01*
X477364D01*
Y-8037D01*
X478881D01*
Y-8005D01*
X478945D01*
Y-7972D01*
X478977D01*
Y-7940D01*
Y-7908D01*
X479010D01*
Y-7876D01*
Y-7843D01*
Y-7811D01*
Y-7779D01*
Y-7747D01*
Y-7714D01*
Y-7682D01*
Y-7650D01*
Y-7618D01*
Y-7585D01*
Y-7553D01*
Y-7521D01*
Y-7489D01*
Y-7456D01*
Y-7424D01*
Y-7392D01*
Y-7360D01*
Y-7327D01*
Y-7295D01*
Y-7263D01*
Y-7231D01*
Y-7198D01*
Y-7166D01*
Y-7134D01*
Y-7102D01*
Y-7069D01*
Y-7037D01*
Y-7005D01*
Y-6972D01*
Y-6940D01*
Y-6908D01*
Y-6876D01*
Y-6843D01*
Y-6811D01*
Y-6779D01*
Y-6747D01*
Y-6714D01*
Y-6682D01*
Y-6650D01*
Y-6617D01*
Y-6585D01*
Y-6553D01*
Y-6521D01*
Y-6488D01*
Y-6456D01*
Y-6424D01*
Y-6392D01*
Y-6359D01*
Y-6327D01*
Y-6295D01*
Y-6263D01*
Y-6230D01*
Y-6198D01*
Y-6166D01*
Y-6134D01*
Y-6101D01*
Y-6069D01*
Y-6037D01*
Y-6005D01*
Y-5972D01*
X479042D01*
Y-5940D01*
Y-5908D01*
X479107D01*
Y-5875D01*
X481268D01*
Y-5908D01*
X481333D01*
Y-5940D01*
Y-5972D01*
X481365D01*
Y-6005D01*
Y-6037D01*
Y-6069D01*
Y-6101D01*
Y-6134D01*
Y-6166D01*
Y-6198D01*
Y-6230D01*
Y-6263D01*
Y-6295D01*
Y-6327D01*
Y-6359D01*
Y-6392D01*
Y-6424D01*
Y-6456D01*
Y-6488D01*
Y-6521D01*
Y-6553D01*
Y-6585D01*
Y-6617D01*
Y-6650D01*
Y-6682D01*
Y-6714D01*
Y-6747D01*
Y-6779D01*
Y-6811D01*
Y-6843D01*
Y-6876D01*
Y-6908D01*
Y-6940D01*
Y-6972D01*
Y-7005D01*
Y-7037D01*
Y-7069D01*
Y-7102D01*
Y-7134D01*
Y-7166D01*
Y-7198D01*
Y-7231D01*
Y-7263D01*
Y-7295D01*
Y-7327D01*
Y-7360D01*
Y-7392D01*
Y-7424D01*
Y-7456D01*
Y-7489D01*
Y-7521D01*
Y-7553D01*
Y-7585D01*
Y-7618D01*
Y-7650D01*
Y-7682D01*
Y-7714D01*
Y-7747D01*
Y-7779D01*
Y-7811D01*
Y-7843D01*
Y-7876D01*
Y-7908D01*
Y-7940D01*
X481397D01*
Y-7972D01*
X481429D01*
Y-8005D01*
X481494D01*
Y-8037D01*
X483010D01*
Y-8005D01*
X483075D01*
Y-7972D01*
X483107D01*
Y-7940D01*
Y-7908D01*
X483139D01*
Y-7876D01*
Y-7843D01*
Y-7811D01*
Y-7779D01*
Y-7747D01*
Y-7714D01*
Y-7682D01*
Y-7650D01*
Y-7618D01*
Y-7585D01*
Y-7553D01*
Y-7521D01*
Y-7489D01*
Y-7456D01*
Y-7424D01*
Y-7392D01*
Y-7360D01*
Y-7327D01*
Y-7295D01*
Y-7263D01*
Y-7231D01*
Y-7198D01*
Y-7166D01*
Y-7134D01*
Y-7102D01*
Y-7069D01*
Y-7037D01*
Y-7005D01*
Y-6972D01*
Y-6940D01*
Y-6908D01*
Y-6876D01*
Y-6843D01*
Y-6811D01*
Y-6779D01*
Y-6747D01*
Y-6714D01*
Y-6682D01*
Y-6650D01*
Y-6617D01*
Y-6585D01*
Y-6553D01*
Y-6521D01*
Y-6488D01*
Y-6456D01*
Y-6424D01*
Y-6392D01*
Y-6359D01*
Y-6327D01*
Y-6295D01*
Y-6263D01*
Y-6230D01*
Y-6198D01*
Y-6166D01*
Y-6134D01*
Y-6101D01*
Y-6069D01*
Y-6037D01*
Y-6005D01*
Y-5972D01*
Y-5940D01*
Y-5908D01*
Y-5875D01*
Y-5843D01*
Y-5811D01*
Y-5779D01*
Y-5746D01*
Y-5714D01*
Y-5682D01*
Y-5650D01*
Y-5617D01*
Y-5585D01*
Y-5553D01*
Y-5521D01*
Y-5488D01*
Y-5456D01*
Y-5424D01*
Y-5392D01*
Y-5359D01*
Y-5327D01*
Y-5295D01*
Y-5263D01*
Y-5230D01*
Y-5198D01*
Y-5166D01*
Y-5133D01*
Y-5101D01*
Y-5069D01*
Y-5037D01*
Y-5004D01*
Y-4972D01*
Y-4940D01*
Y-4908D01*
Y-4875D01*
Y-4843D01*
Y-4811D01*
Y-4779D01*
Y-4746D01*
Y-4714D01*
Y-4682D01*
Y-4650D01*
Y-4617D01*
Y-4585D01*
Y-4553D01*
Y-4521D01*
Y-4488D01*
Y-4456D01*
Y-4424D01*
Y-4391D01*
Y-4359D01*
Y-4327D01*
Y-4295D01*
Y-4262D01*
Y-4230D01*
Y-4198D01*
Y-4166D01*
Y-4133D01*
Y-4101D01*
Y-4069D01*
Y-4037D01*
Y-4004D01*
Y-3972D01*
Y-3940D01*
Y-3907D01*
Y-3875D01*
Y-3843D01*
Y-3811D01*
Y-3779D01*
Y-3746D01*
Y-3714D01*
Y-3682D01*
Y-3650D01*
Y-3617D01*
Y-3585D01*
Y-3553D01*
Y-3520D01*
Y-3488D01*
Y-3456D01*
Y-3424D01*
Y-3391D01*
Y-3359D01*
Y-3327D01*
Y-3295D01*
Y-3262D01*
Y-3230D01*
Y-3198D01*
Y-3165D01*
Y-3133D01*
Y-3101D01*
Y-3069D01*
Y-3036D01*
Y-3004D01*
Y-2972D01*
Y-2940D01*
Y-2907D01*
Y-2875D01*
Y-2843D01*
Y-2811D01*
Y-2778D01*
Y-2746D01*
Y-2714D01*
Y-2682D01*
Y-2649D01*
Y-2617D01*
Y-2585D01*
Y-2553D01*
Y-2520D01*
Y-2488D01*
Y-2456D01*
Y-2424D01*
Y-2391D01*
Y-2359D01*
Y-2327D01*
Y-2294D01*
Y-2262D01*
Y-2230D01*
X483107D01*
Y-2198D01*
Y-2165D01*
Y-2133D01*
Y-2101D01*
X483075D01*
Y-2069D01*
Y-2036D01*
Y-2004D01*
X483042D01*
Y-1972D01*
X483010D01*
Y-1940D01*
X482978D01*
Y-1907D01*
X482946D01*
Y-1875D01*
X482913D01*
Y-1843D01*
X482881D01*
Y-1811D01*
X482849D01*
Y-1778D01*
X482817D01*
Y-1746D01*
X482784D01*
Y-1714D01*
X482752D01*
Y-1681D01*
X482720D01*
Y-1649D01*
X482688D01*
Y-1617D01*
X482655D01*
Y-1585D01*
X482623D01*
Y-1552D01*
X482591D01*
Y-1520D01*
X482559D01*
Y-1488D01*
X482526D01*
Y-1456D01*
X482494D01*
Y-1423D01*
X482462D01*
Y-1391D01*
X482430D01*
Y-1359D01*
X482397D01*
Y-1327D01*
X482365D01*
Y-1294D01*
X482333D01*
Y-1262D01*
X482301D01*
Y-1230D01*
X482268D01*
Y-1198D01*
X482236D01*
Y-1165D01*
X482204D01*
Y-1133D01*
X482171D01*
Y-1101D01*
X482107D01*
Y-1068D01*
X482042D01*
Y-1036D01*
X481913D01*
Y-1004D01*
D02*
G37*
G36*
X479687Y10449D02*
X479107D01*
Y10417D01*
Y10384D01*
Y10352D01*
Y10320D01*
Y10288D01*
Y10255D01*
Y10223D01*
Y10191D01*
Y10159D01*
Y10126D01*
Y10094D01*
Y10062D01*
Y10029D01*
Y9997D01*
Y9965D01*
Y9933D01*
Y9900D01*
Y9868D01*
Y9836D01*
Y9804D01*
Y9771D01*
Y9739D01*
Y9707D01*
Y9675D01*
Y9642D01*
Y9610D01*
Y9578D01*
Y9546D01*
Y9513D01*
Y9481D01*
Y9449D01*
Y9417D01*
Y9384D01*
Y9352D01*
Y9320D01*
Y9287D01*
Y9255D01*
Y9223D01*
Y9191D01*
Y9159D01*
Y9126D01*
Y9094D01*
Y9062D01*
Y9029D01*
Y8997D01*
Y8965D01*
Y8933D01*
Y8900D01*
Y8868D01*
Y8836D01*
Y8804D01*
Y8771D01*
Y8739D01*
Y8707D01*
Y8675D01*
Y8642D01*
Y8610D01*
Y8578D01*
Y8546D01*
Y8513D01*
Y8481D01*
Y8449D01*
Y8416D01*
Y8384D01*
Y8352D01*
Y8320D01*
Y8287D01*
Y8255D01*
Y8223D01*
Y8191D01*
Y8158D01*
Y8126D01*
Y8094D01*
Y8062D01*
Y8029D01*
Y7997D01*
Y7965D01*
Y7932D01*
Y7900D01*
Y7868D01*
Y7836D01*
Y7803D01*
Y7771D01*
Y7739D01*
Y7707D01*
Y7674D01*
Y7642D01*
Y7610D01*
Y7578D01*
Y7545D01*
Y7513D01*
Y7481D01*
Y7449D01*
Y7416D01*
Y7384D01*
Y7352D01*
Y7320D01*
Y7287D01*
Y7255D01*
Y7223D01*
Y7191D01*
Y7158D01*
Y7126D01*
Y7094D01*
Y7062D01*
Y7029D01*
Y6997D01*
Y6965D01*
Y6932D01*
Y6900D01*
Y6868D01*
Y6836D01*
Y6803D01*
Y6771D01*
Y6739D01*
Y6707D01*
Y6674D01*
Y6642D01*
Y6610D01*
Y6577D01*
Y6545D01*
Y6513D01*
Y6481D01*
Y6448D01*
Y6416D01*
Y6384D01*
Y6352D01*
Y6319D01*
Y6287D01*
Y6255D01*
Y6223D01*
Y6190D01*
Y6158D01*
Y6126D01*
Y6094D01*
Y6061D01*
Y6029D01*
Y5997D01*
Y5965D01*
Y5932D01*
Y5900D01*
Y5868D01*
Y5835D01*
Y5803D01*
Y5771D01*
Y5739D01*
Y5706D01*
Y5674D01*
Y5642D01*
Y5610D01*
Y5577D01*
Y5545D01*
Y5513D01*
Y5481D01*
Y5448D01*
Y5416D01*
Y5384D01*
Y5352D01*
Y5319D01*
Y5287D01*
Y5255D01*
Y5223D01*
Y5190D01*
Y5158D01*
Y5126D01*
Y5094D01*
Y5061D01*
Y5029D01*
Y4997D01*
Y4964D01*
Y4932D01*
Y4900D01*
Y4868D01*
Y4835D01*
Y4803D01*
Y4771D01*
Y4739D01*
Y4706D01*
Y4674D01*
Y4642D01*
Y4610D01*
Y4577D01*
Y4545D01*
Y4513D01*
Y4481D01*
Y4448D01*
Y4416D01*
Y4384D01*
Y4352D01*
Y4319D01*
Y4287D01*
Y4255D01*
Y4222D01*
Y4190D01*
Y4158D01*
Y4126D01*
Y4093D01*
Y4061D01*
Y4029D01*
Y3997D01*
Y3964D01*
Y3932D01*
Y3900D01*
Y3867D01*
Y3835D01*
Y3803D01*
Y3771D01*
Y3739D01*
Y3706D01*
Y3674D01*
Y3642D01*
Y3609D01*
Y3577D01*
Y3545D01*
Y3513D01*
Y3480D01*
Y3448D01*
Y3416D01*
Y3384D01*
Y3351D01*
Y3319D01*
Y3287D01*
Y3255D01*
Y3222D01*
Y3190D01*
Y3158D01*
Y3125D01*
Y3093D01*
Y3061D01*
Y3029D01*
Y2997D01*
Y2964D01*
Y2932D01*
Y2900D01*
Y2867D01*
Y2835D01*
Y2803D01*
Y2771D01*
Y2738D01*
Y2706D01*
Y2674D01*
Y2642D01*
Y2609D01*
Y2577D01*
Y2545D01*
Y2513D01*
Y2480D01*
Y2448D01*
Y2416D01*
Y2383D01*
Y2351D01*
Y2319D01*
Y2287D01*
Y2254D01*
Y2222D01*
Y2190D01*
Y2158D01*
Y2125D01*
Y2093D01*
Y2061D01*
Y2029D01*
Y1996D01*
Y1964D01*
Y1932D01*
Y1900D01*
Y1867D01*
Y1835D01*
Y1803D01*
Y1770D01*
Y1738D01*
Y1706D01*
Y1674D01*
Y1641D01*
Y1609D01*
Y1577D01*
Y1545D01*
Y1512D01*
Y1480D01*
Y1448D01*
Y1416D01*
Y1383D01*
Y1351D01*
Y1319D01*
Y1287D01*
Y1254D01*
Y1222D01*
Y1190D01*
Y1158D01*
Y1125D01*
Y1093D01*
Y1061D01*
Y1029D01*
Y996D01*
Y964D01*
Y932D01*
Y900D01*
Y867D01*
Y835D01*
Y803D01*
Y770D01*
Y738D01*
Y706D01*
Y674D01*
Y641D01*
Y609D01*
Y577D01*
Y545D01*
Y512D01*
Y480D01*
Y448D01*
Y416D01*
Y383D01*
Y351D01*
Y319D01*
Y286D01*
Y254D01*
Y222D01*
Y190D01*
Y157D01*
Y125D01*
Y93D01*
Y61D01*
Y28D01*
Y-4D01*
Y-36D01*
Y-68D01*
Y-101D01*
Y-133D01*
Y-165D01*
Y-197D01*
Y-230D01*
X479074D01*
Y-262D01*
X479042D01*
Y-294D01*
X479010D01*
Y-326D01*
X478977D01*
Y-359D01*
X478945D01*
Y-391D01*
X478913D01*
Y-423D01*
X478881D01*
Y-455D01*
X478849D01*
Y-488D01*
X478816D01*
Y-520D01*
X478784D01*
Y-552D01*
X478752D01*
Y-585D01*
X478719D01*
Y-617D01*
X478687D01*
Y-649D01*
X478655D01*
Y-681D01*
X478623D01*
Y-714D01*
X478590D01*
Y-746D01*
X478558D01*
Y-778D01*
X478494D01*
Y-810D01*
X478461D01*
Y-843D01*
X478429D01*
Y-875D01*
X478397D01*
Y-907D01*
X478365D01*
Y-939D01*
X478332D01*
Y-972D01*
X478300D01*
Y-1004D01*
X478268D01*
Y-1036D01*
X478235D01*
Y-1068D01*
X478203D01*
Y-1101D01*
X478171D01*
Y-1133D01*
X478139D01*
Y-1165D01*
X478106D01*
Y-1198D01*
X478074D01*
Y-1230D01*
X478042D01*
Y-1262D01*
X478010D01*
Y-1294D01*
X477977D01*
Y-1327D01*
X477945D01*
Y-1359D01*
X477913D01*
Y-1391D01*
X477881D01*
Y-1423D01*
X477848D01*
Y-1456D01*
X477816D01*
Y-1488D01*
X477784D01*
Y-1520D01*
X477752D01*
Y-1552D01*
X477719D01*
Y-1585D01*
X477687D01*
Y-1617D01*
X477655D01*
Y-1649D01*
X477623D01*
Y-1681D01*
X477590D01*
Y-1714D01*
X477558D01*
Y-1746D01*
X477526D01*
Y-1778D01*
X477493D01*
Y-1811D01*
X477461D01*
Y-1843D01*
X477429D01*
Y-1875D01*
X477397D01*
Y-1907D01*
X477364D01*
Y-1940D01*
X477332D01*
Y-1972D01*
X477300D01*
Y-2004D01*
X477268D01*
Y-2036D01*
X477235D01*
Y-2069D01*
X477203D01*
Y-2101D01*
X477171D01*
Y-2133D01*
X477139D01*
Y-2165D01*
X477106D01*
Y-2198D01*
X477074D01*
Y-2230D01*
X477042D01*
Y-2262D01*
X477009D01*
Y-2294D01*
X476977D01*
Y-2327D01*
X476945D01*
Y-2359D01*
X476913D01*
Y-2391D01*
X476881D01*
Y-2424D01*
X476848D01*
Y-2456D01*
X476816D01*
Y-2488D01*
X476784D01*
Y-2520D01*
X476751D01*
Y-2553D01*
X476719D01*
Y-2585D01*
X476687D01*
Y-2617D01*
X476655D01*
Y-2649D01*
X476622D01*
Y-2682D01*
X476590D01*
Y-2714D01*
X476558D01*
Y-2746D01*
X476526D01*
Y-2778D01*
X476493D01*
Y-2811D01*
X476461D01*
Y-2843D01*
X476429D01*
Y-2875D01*
X476397D01*
Y-2907D01*
X476364D01*
Y-2940D01*
X476300D01*
Y-2972D01*
X476267D01*
Y-3004D01*
X476235D01*
Y-3036D01*
X476203D01*
Y-3069D01*
X476171D01*
Y-3101D01*
X476138D01*
Y-3133D01*
X476106D01*
Y-3165D01*
X476074D01*
Y-3198D01*
X476042D01*
Y-3230D01*
X476009D01*
Y-3262D01*
X475977D01*
Y-3295D01*
X475945D01*
Y-3327D01*
X475913D01*
Y-3359D01*
X475880D01*
Y-3391D01*
X475848D01*
Y-3424D01*
X475816D01*
Y-3456D01*
X475784D01*
Y-3488D01*
Y-3520D01*
X475751D01*
Y-3553D01*
X475719D01*
Y-3585D01*
Y-3617D01*
X475687D01*
Y-3650D01*
Y-3682D01*
X475655D01*
Y-3714D01*
Y-3746D01*
Y-3779D01*
Y-3811D01*
Y-3843D01*
Y-3875D01*
Y-3907D01*
Y-3940D01*
Y-3972D01*
Y-4004D01*
Y-4037D01*
Y-4069D01*
Y-4101D01*
Y-4133D01*
Y-4166D01*
Y-4198D01*
Y-4230D01*
Y-4262D01*
Y-4295D01*
Y-4327D01*
Y-4359D01*
Y-4391D01*
Y-4424D01*
Y-4456D01*
Y-4488D01*
Y-4521D01*
Y-4553D01*
Y-4585D01*
Y-4617D01*
Y-4650D01*
Y-4682D01*
Y-4714D01*
Y-4746D01*
Y-4779D01*
Y-4811D01*
Y-4843D01*
Y-4875D01*
Y-4908D01*
Y-4940D01*
Y-4972D01*
Y-5004D01*
Y-5037D01*
Y-5069D01*
Y-5101D01*
Y-5133D01*
X475687D01*
Y-5166D01*
X475719D01*
Y-5198D01*
Y-5230D01*
X475751D01*
Y-5263D01*
X475784D01*
Y-5295D01*
Y-5327D01*
X475816D01*
Y-5359D01*
X475848D01*
Y-5392D01*
X475880D01*
Y-5424D01*
X475913D01*
Y-5456D01*
X475945D01*
Y-5488D01*
X475977D01*
Y-5521D01*
X476009D01*
Y-5553D01*
X476042D01*
Y-5585D01*
X476074D01*
Y-5617D01*
X476138D01*
Y-5585D01*
X476171D01*
Y-5553D01*
X476203D01*
Y-5521D01*
X476235D01*
Y-5488D01*
X476267D01*
Y-5456D01*
X476300D01*
Y-5424D01*
X476332D01*
Y-5392D01*
X476364D01*
Y-5359D01*
X476397D01*
Y-5327D01*
X476429D01*
Y-5295D01*
X476461D01*
Y-5263D01*
X476493D01*
Y-5230D01*
X476526D01*
Y-5198D01*
X476558D01*
Y-5166D01*
X476590D01*
Y-5133D01*
X476622D01*
Y-5101D01*
X476655D01*
Y-5069D01*
X476687D01*
Y-5037D01*
X476719D01*
Y-5004D01*
X476751D01*
Y-4972D01*
X476784D01*
Y-4940D01*
X476816D01*
Y-4908D01*
X476848D01*
Y-4875D01*
X476881D01*
Y-4843D01*
X476945D01*
Y-4811D01*
X476977D01*
Y-4779D01*
X477009D01*
Y-4746D01*
X477042D01*
Y-4714D01*
X477074D01*
Y-4682D01*
X477106D01*
Y-4650D01*
X477139D01*
Y-4617D01*
X477171D01*
Y-4585D01*
X477203D01*
Y-4553D01*
X477235D01*
Y-4521D01*
X477268D01*
Y-4488D01*
X477300D01*
Y-4456D01*
X477332D01*
Y-4424D01*
X477364D01*
Y-4391D01*
X477397D01*
Y-4359D01*
X477429D01*
Y-4327D01*
X477461D01*
Y-4295D01*
X477493D01*
Y-4262D01*
X477526D01*
Y-4230D01*
X477558D01*
Y-4198D01*
X477590D01*
Y-4166D01*
X477623D01*
Y-4133D01*
X477655D01*
Y-4101D01*
X477687D01*
Y-4069D01*
X477719D01*
Y-4037D01*
X477752D01*
Y-4004D01*
X477784D01*
Y-3972D01*
X477816D01*
Y-3940D01*
X477848D01*
Y-3907D01*
X477881D01*
Y-3875D01*
X477913D01*
Y-3843D01*
X477945D01*
Y-3811D01*
X477977D01*
Y-3779D01*
X478010D01*
Y-3746D01*
X478042D01*
Y-3714D01*
X478074D01*
Y-3682D01*
X478106D01*
Y-3650D01*
X478139D01*
Y-3617D01*
X478171D01*
Y-3585D01*
X478203D01*
Y-3553D01*
X478235D01*
Y-3520D01*
X478268D01*
Y-3488D01*
X478300D01*
Y-3456D01*
X478332D01*
Y-3424D01*
X478365D01*
Y-3391D01*
X478397D01*
Y-3359D01*
X478429D01*
Y-3327D01*
X478461D01*
Y-3295D01*
X478494D01*
Y-3262D01*
X478526D01*
Y-3230D01*
X478558D01*
Y-3198D01*
X478590D01*
Y-3165D01*
X478623D01*
Y-3133D01*
X478655D01*
Y-3101D01*
X478687D01*
Y-3069D01*
X478719D01*
Y-3036D01*
X478752D01*
Y-3004D01*
X478784D01*
Y-2972D01*
X478816D01*
Y-2940D01*
X478849D01*
Y-2907D01*
X478881D01*
Y-2875D01*
X478913D01*
Y-2843D01*
X478945D01*
Y-2811D01*
X478977D01*
Y-2778D01*
X479010D01*
Y-2746D01*
X479042D01*
Y-2714D01*
X479074D01*
Y-2682D01*
X479107D01*
Y-2649D01*
X479139D01*
Y-2617D01*
X479171D01*
Y-2585D01*
X479203D01*
Y-2553D01*
X479236D01*
Y-2520D01*
X479268D01*
Y-2488D01*
X479300D01*
Y-2456D01*
X479332D01*
Y-2424D01*
X479365D01*
Y-2391D01*
X479397D01*
Y-2359D01*
X479429D01*
Y-2327D01*
X479461D01*
Y-2294D01*
X479494D01*
Y-2262D01*
X479526D01*
Y-2230D01*
X479558D01*
Y-2198D01*
X479591D01*
Y-2165D01*
X479623D01*
Y-2133D01*
X479687D01*
Y-2101D01*
X479719D01*
Y-2069D01*
X479752D01*
Y-2036D01*
X479784D01*
Y-2004D01*
X479816D01*
Y-1972D01*
X479849D01*
Y-1940D01*
X479881D01*
Y-1907D01*
X479913D01*
Y-1875D01*
X479945D01*
Y-1843D01*
X479978D01*
Y-1811D01*
X480010D01*
Y-1778D01*
X480042D01*
Y-1746D01*
X480074D01*
Y-1714D01*
X480107D01*
Y-1681D01*
X480139D01*
Y-1649D01*
X480171D01*
Y-1617D01*
X480203D01*
Y-1585D01*
X480236D01*
Y-1552D01*
X480268D01*
Y-1520D01*
X480300D01*
Y-1488D01*
X480333D01*
Y-1456D01*
X480365D01*
Y-1423D01*
X480397D01*
Y-1391D01*
X480429D01*
Y-1359D01*
X480462D01*
Y-1327D01*
X480494D01*
Y-1294D01*
X480526D01*
Y-1262D01*
X480558D01*
Y-1230D01*
X480591D01*
Y-1198D01*
X480623D01*
Y-1165D01*
X480655D01*
Y-1133D01*
Y-1101D01*
X480687D01*
Y-1068D01*
X480720D01*
Y-1036D01*
Y-1004D01*
X480752D01*
Y-972D01*
Y-939D01*
X480784D01*
Y-907D01*
Y-875D01*
X480816D01*
Y-843D01*
Y-810D01*
Y-778D01*
Y-746D01*
X480849D01*
Y-714D01*
Y-681D01*
Y-649D01*
Y-617D01*
Y-585D01*
Y-552D01*
Y-520D01*
Y-488D01*
Y-455D01*
Y-423D01*
Y-391D01*
Y-359D01*
Y-326D01*
Y-294D01*
Y-262D01*
Y-230D01*
Y-197D01*
Y-165D01*
Y-133D01*
Y-101D01*
Y-68D01*
Y-36D01*
Y-4D01*
Y28D01*
Y61D01*
Y93D01*
Y125D01*
Y157D01*
Y190D01*
Y222D01*
Y254D01*
Y286D01*
Y319D01*
Y351D01*
Y383D01*
Y416D01*
Y448D01*
Y480D01*
Y512D01*
Y545D01*
Y577D01*
Y609D01*
Y641D01*
Y674D01*
Y706D01*
Y738D01*
Y770D01*
Y803D01*
Y835D01*
Y867D01*
Y900D01*
Y932D01*
Y964D01*
Y996D01*
Y1029D01*
Y1061D01*
Y1093D01*
Y1125D01*
Y1158D01*
Y1190D01*
Y1222D01*
Y1254D01*
Y1287D01*
Y1319D01*
Y1351D01*
Y1383D01*
Y1416D01*
Y1448D01*
Y1480D01*
Y1512D01*
Y1545D01*
Y1577D01*
Y1609D01*
Y1641D01*
Y1674D01*
Y1706D01*
Y1738D01*
Y1770D01*
Y1803D01*
Y1835D01*
Y1867D01*
Y1900D01*
Y1932D01*
Y1964D01*
Y1996D01*
Y2029D01*
Y2061D01*
Y2093D01*
Y2125D01*
Y2158D01*
Y2190D01*
Y2222D01*
Y2254D01*
Y2287D01*
Y2319D01*
Y2351D01*
Y2383D01*
Y2416D01*
Y2448D01*
Y2480D01*
Y2513D01*
Y2545D01*
Y2577D01*
Y2609D01*
Y2642D01*
Y2674D01*
Y2706D01*
Y2738D01*
Y2771D01*
Y2803D01*
Y2835D01*
Y2867D01*
Y2900D01*
Y2932D01*
Y2964D01*
Y2997D01*
Y3029D01*
Y3061D01*
Y3093D01*
Y3125D01*
Y3158D01*
Y3190D01*
Y3222D01*
Y3255D01*
Y3287D01*
Y3319D01*
Y3351D01*
Y3384D01*
Y3416D01*
Y3448D01*
Y3480D01*
Y3513D01*
Y3545D01*
Y3577D01*
Y3609D01*
Y3642D01*
Y3674D01*
Y3706D01*
Y3739D01*
Y3771D01*
Y3803D01*
Y3835D01*
Y3867D01*
Y3900D01*
Y3932D01*
Y3964D01*
Y3997D01*
Y4029D01*
Y4061D01*
Y4093D01*
Y4126D01*
Y4158D01*
Y4190D01*
Y4222D01*
Y4255D01*
Y4287D01*
Y4319D01*
Y4352D01*
Y4384D01*
Y4416D01*
Y4448D01*
Y4481D01*
Y4513D01*
Y4545D01*
Y4577D01*
Y4610D01*
Y4642D01*
Y4674D01*
Y4706D01*
Y4739D01*
Y4771D01*
Y4803D01*
Y4835D01*
Y4868D01*
Y4900D01*
Y4932D01*
Y4964D01*
Y4997D01*
Y5029D01*
Y5061D01*
Y5094D01*
Y5126D01*
Y5158D01*
Y5190D01*
Y5223D01*
Y5255D01*
Y5287D01*
Y5319D01*
Y5352D01*
Y5384D01*
Y5416D01*
Y5448D01*
Y5481D01*
Y5513D01*
Y5545D01*
Y5577D01*
Y5610D01*
Y5642D01*
Y5674D01*
Y5706D01*
Y5739D01*
Y5771D01*
Y5803D01*
Y5835D01*
Y5868D01*
Y5900D01*
Y5932D01*
Y5965D01*
Y5997D01*
Y6029D01*
Y6061D01*
Y6094D01*
Y6126D01*
Y6158D01*
Y6190D01*
Y6223D01*
Y6255D01*
Y6287D01*
Y6319D01*
Y6352D01*
Y6384D01*
Y6416D01*
Y6448D01*
Y6481D01*
Y6513D01*
Y6545D01*
Y6577D01*
Y6610D01*
Y6642D01*
Y6674D01*
Y6707D01*
Y6739D01*
Y6771D01*
Y6803D01*
Y6836D01*
Y6868D01*
Y6900D01*
Y6932D01*
Y6965D01*
Y6997D01*
Y7029D01*
Y7062D01*
Y7094D01*
Y7126D01*
Y7158D01*
Y7191D01*
Y7223D01*
Y7255D01*
Y7287D01*
Y7320D01*
Y7352D01*
Y7384D01*
Y7416D01*
Y7449D01*
Y7481D01*
Y7513D01*
Y7545D01*
Y7578D01*
Y7610D01*
Y7642D01*
Y7674D01*
Y7707D01*
Y7739D01*
Y7771D01*
Y7803D01*
Y7836D01*
Y7868D01*
Y7900D01*
Y7932D01*
Y7965D01*
Y7997D01*
Y8029D01*
Y8062D01*
Y8094D01*
Y8126D01*
Y8158D01*
Y8191D01*
Y8223D01*
Y8255D01*
Y8287D01*
Y8320D01*
Y8352D01*
Y8384D01*
Y8416D01*
Y8449D01*
Y8481D01*
Y8513D01*
Y8546D01*
Y8578D01*
Y8610D01*
Y8642D01*
Y8675D01*
Y8707D01*
Y8739D01*
Y8771D01*
Y8804D01*
Y8836D01*
Y8868D01*
Y8900D01*
Y8933D01*
Y8965D01*
Y8997D01*
Y9029D01*
Y9062D01*
Y9094D01*
Y9126D01*
Y9159D01*
Y9191D01*
Y9223D01*
Y9255D01*
Y9287D01*
X480816D01*
Y9320D01*
Y9352D01*
Y9384D01*
Y9417D01*
X480784D01*
Y9449D01*
Y9481D01*
X480752D01*
Y9513D01*
X480720D01*
Y9546D01*
X480687D01*
Y9578D01*
X480655D01*
Y9610D01*
X480623D01*
Y9642D01*
X480591D01*
Y9675D01*
X480558D01*
Y9707D01*
X480526D01*
Y9739D01*
X480494D01*
Y9771D01*
X480462D01*
Y9804D01*
X480429D01*
Y9836D01*
X480397D01*
Y9868D01*
X480365D01*
Y9900D01*
X480333D01*
Y9933D01*
X480300D01*
Y9965D01*
X480268D01*
Y9997D01*
X480236D01*
Y10029D01*
X480203D01*
Y10062D01*
X480171D01*
Y10094D01*
X480139D01*
Y10126D01*
X480107D01*
Y10159D01*
X480074D01*
Y10191D01*
X480042D01*
Y10223D01*
X480010D01*
Y10255D01*
X479978D01*
Y10288D01*
X479945D01*
Y10320D01*
X479913D01*
Y10352D01*
X479881D01*
Y10384D01*
X479816D01*
Y10417D01*
X479687D01*
Y10449D01*
D02*
G37*
G36*
X495302Y-1004D02*
X490850D01*
Y-1036D01*
X490785D01*
Y-1068D01*
X490753D01*
Y-1101D01*
X490721D01*
Y-1133D01*
X490689D01*
Y-1165D01*
Y-1198D01*
Y-1230D01*
Y-1262D01*
Y-1294D01*
Y-1327D01*
Y-1359D01*
Y-1391D01*
Y-1423D01*
Y-1456D01*
Y-1488D01*
Y-1520D01*
Y-1552D01*
Y-1585D01*
Y-1617D01*
Y-1649D01*
Y-1681D01*
Y-1714D01*
Y-1746D01*
Y-1778D01*
Y-1811D01*
Y-1843D01*
Y-1875D01*
Y-1907D01*
Y-1940D01*
Y-1972D01*
Y-2004D01*
Y-2036D01*
Y-2069D01*
Y-2101D01*
Y-2133D01*
Y-2165D01*
Y-2198D01*
Y-2230D01*
Y-2262D01*
Y-2294D01*
Y-2327D01*
Y-2359D01*
Y-2391D01*
Y-2424D01*
Y-2456D01*
Y-2488D01*
Y-2520D01*
Y-2553D01*
Y-2585D01*
Y-2617D01*
Y-2649D01*
Y-2682D01*
Y-2714D01*
Y-2746D01*
Y-2778D01*
Y-2811D01*
Y-2843D01*
Y-2875D01*
Y-2907D01*
Y-2940D01*
Y-2972D01*
Y-3004D01*
Y-3036D01*
Y-3069D01*
Y-3101D01*
Y-3133D01*
Y-3165D01*
Y-3198D01*
Y-3230D01*
Y-3262D01*
Y-3295D01*
Y-3327D01*
Y-3359D01*
Y-3391D01*
Y-3424D01*
Y-3456D01*
Y-3488D01*
Y-3520D01*
Y-3553D01*
Y-3585D01*
Y-3617D01*
Y-3650D01*
Y-3682D01*
Y-3714D01*
Y-3746D01*
Y-3779D01*
Y-3811D01*
Y-3843D01*
Y-3875D01*
Y-3907D01*
Y-3940D01*
Y-3972D01*
Y-4004D01*
Y-4037D01*
Y-4069D01*
Y-4101D01*
Y-4133D01*
Y-4166D01*
Y-4198D01*
Y-4230D01*
Y-4262D01*
Y-4295D01*
Y-4327D01*
Y-4359D01*
Y-4391D01*
Y-4424D01*
Y-4456D01*
Y-4488D01*
Y-4521D01*
Y-4553D01*
Y-4585D01*
Y-4617D01*
Y-4650D01*
Y-4682D01*
Y-4714D01*
Y-4746D01*
Y-4779D01*
Y-4811D01*
Y-4843D01*
Y-4875D01*
Y-4908D01*
Y-4940D01*
Y-4972D01*
Y-5004D01*
Y-5037D01*
Y-5069D01*
Y-5101D01*
Y-5133D01*
Y-5166D01*
Y-5198D01*
Y-5230D01*
Y-5263D01*
Y-5295D01*
Y-5327D01*
Y-5359D01*
Y-5392D01*
Y-5424D01*
Y-5456D01*
Y-5488D01*
Y-5521D01*
Y-5553D01*
Y-5585D01*
Y-5617D01*
Y-5650D01*
Y-5682D01*
Y-5714D01*
Y-5746D01*
Y-5779D01*
Y-5811D01*
Y-5843D01*
Y-5875D01*
Y-5908D01*
Y-5940D01*
Y-5972D01*
Y-6005D01*
Y-6037D01*
Y-6069D01*
Y-6101D01*
Y-6134D01*
Y-6166D01*
Y-6198D01*
Y-6230D01*
Y-6263D01*
Y-6295D01*
Y-6327D01*
Y-6359D01*
Y-6392D01*
Y-6424D01*
Y-6456D01*
Y-6488D01*
Y-6521D01*
Y-6553D01*
Y-6585D01*
Y-6617D01*
Y-6650D01*
Y-6682D01*
Y-6714D01*
Y-6747D01*
Y-6779D01*
Y-6811D01*
Y-6843D01*
Y-6876D01*
Y-6908D01*
Y-6940D01*
Y-6972D01*
Y-7005D01*
Y-7037D01*
Y-7069D01*
Y-7102D01*
Y-7134D01*
Y-7166D01*
Y-7198D01*
Y-7231D01*
Y-7263D01*
Y-7295D01*
Y-7327D01*
Y-7360D01*
Y-7392D01*
Y-7424D01*
Y-7456D01*
Y-7489D01*
Y-7521D01*
Y-7553D01*
Y-7585D01*
Y-7618D01*
Y-7650D01*
Y-7682D01*
Y-7714D01*
Y-7747D01*
Y-7779D01*
Y-7811D01*
Y-7843D01*
Y-7876D01*
Y-7908D01*
Y-7940D01*
X490721D01*
Y-7972D01*
X490753D01*
Y-8005D01*
X490785D01*
Y-8037D01*
X495399D01*
Y-8005D01*
X495528D01*
Y-7972D01*
X495592D01*
Y-7940D01*
X495625D01*
Y-7908D01*
X495657D01*
Y-7876D01*
X495689D01*
Y-7843D01*
X495721D01*
Y-7811D01*
X495754D01*
Y-7779D01*
X495786D01*
Y-7747D01*
X495818D01*
Y-7714D01*
X495850D01*
Y-7682D01*
X495883D01*
Y-7650D01*
X495915D01*
Y-7618D01*
X495947D01*
Y-7585D01*
X495979D01*
Y-7553D01*
X496012D01*
Y-7521D01*
X496044D01*
Y-7489D01*
X496076D01*
Y-7456D01*
X496108D01*
Y-7424D01*
X496141D01*
Y-7392D01*
X496173D01*
Y-7360D01*
X496205D01*
Y-7327D01*
X496238D01*
Y-7295D01*
X496270D01*
Y-7263D01*
X496302D01*
Y-7231D01*
X496334D01*
Y-7198D01*
X496367D01*
Y-7166D01*
X496399D01*
Y-7134D01*
X496431D01*
Y-7102D01*
X496463D01*
Y-7069D01*
X496496D01*
Y-7037D01*
X496528D01*
Y-7005D01*
Y-6972D01*
Y-6940D01*
X496560D01*
Y-6908D01*
Y-6876D01*
Y-6843D01*
Y-6811D01*
X496592D01*
Y-6779D01*
Y-6747D01*
Y-6714D01*
Y-6682D01*
Y-6650D01*
Y-6617D01*
Y-6585D01*
Y-6553D01*
Y-6521D01*
Y-6488D01*
Y-6456D01*
Y-6424D01*
Y-6392D01*
Y-6359D01*
Y-6327D01*
Y-6295D01*
Y-6263D01*
Y-6230D01*
Y-6198D01*
Y-6166D01*
Y-6134D01*
Y-6101D01*
Y-6069D01*
Y-6037D01*
Y-6005D01*
Y-5972D01*
Y-5940D01*
Y-5908D01*
Y-5875D01*
Y-5843D01*
Y-5811D01*
Y-5779D01*
Y-5746D01*
Y-5714D01*
Y-5682D01*
Y-5650D01*
Y-5617D01*
Y-5585D01*
Y-5553D01*
Y-5521D01*
Y-5488D01*
Y-5456D01*
Y-5424D01*
Y-5392D01*
Y-5359D01*
Y-5327D01*
Y-5295D01*
Y-5263D01*
Y-5230D01*
Y-5198D01*
Y-5166D01*
Y-5133D01*
Y-5101D01*
Y-5069D01*
Y-5037D01*
Y-5004D01*
Y-4972D01*
Y-4940D01*
Y-4908D01*
Y-4875D01*
Y-4843D01*
Y-4811D01*
Y-4779D01*
Y-4746D01*
Y-4714D01*
Y-4682D01*
Y-4650D01*
Y-4617D01*
Y-4585D01*
Y-4553D01*
Y-4521D01*
Y-4488D01*
Y-4456D01*
Y-4424D01*
Y-4391D01*
Y-4359D01*
Y-4327D01*
Y-4295D01*
Y-4262D01*
Y-4230D01*
Y-4198D01*
Y-4166D01*
Y-4133D01*
Y-4101D01*
Y-4069D01*
Y-4037D01*
Y-4004D01*
Y-3972D01*
Y-3940D01*
Y-3907D01*
Y-3875D01*
Y-3843D01*
Y-3811D01*
Y-3779D01*
Y-3746D01*
Y-3714D01*
Y-3682D01*
Y-3650D01*
Y-3617D01*
Y-3585D01*
Y-3553D01*
Y-3520D01*
Y-3488D01*
Y-3456D01*
Y-3424D01*
Y-3391D01*
Y-3359D01*
Y-3327D01*
Y-3295D01*
Y-3262D01*
Y-3230D01*
Y-3198D01*
Y-3165D01*
Y-3133D01*
Y-3101D01*
Y-3069D01*
Y-3036D01*
Y-3004D01*
Y-2972D01*
Y-2940D01*
Y-2907D01*
Y-2875D01*
Y-2843D01*
Y-2811D01*
Y-2778D01*
Y-2746D01*
Y-2714D01*
Y-2682D01*
Y-2649D01*
Y-2617D01*
Y-2585D01*
Y-2553D01*
Y-2520D01*
Y-2488D01*
Y-2456D01*
Y-2424D01*
Y-2391D01*
Y-2359D01*
Y-2327D01*
Y-2294D01*
Y-2262D01*
Y-2230D01*
X496560D01*
Y-2198D01*
Y-2165D01*
Y-2133D01*
Y-2101D01*
X496528D01*
Y-2069D01*
Y-2036D01*
X496496D01*
Y-2004D01*
X496463D01*
Y-1972D01*
X496431D01*
Y-1940D01*
X496399D01*
Y-1907D01*
X496367D01*
Y-1875D01*
X496334D01*
Y-1843D01*
X496302D01*
Y-1811D01*
X496270D01*
Y-1778D01*
X496238D01*
Y-1746D01*
X496205D01*
Y-1714D01*
X496173D01*
Y-1681D01*
X496141D01*
Y-1649D01*
X496108D01*
Y-1617D01*
X496076D01*
Y-1585D01*
X496044D01*
Y-1552D01*
X496012D01*
Y-1520D01*
X495979D01*
Y-1488D01*
X495947D01*
Y-1456D01*
X495915D01*
Y-1423D01*
X495883D01*
Y-1391D01*
X495850D01*
Y-1359D01*
X495818D01*
Y-1327D01*
X495786D01*
Y-1294D01*
X495754D01*
Y-1262D01*
X495721D01*
Y-1230D01*
X495689D01*
Y-1198D01*
X495657D01*
Y-1165D01*
X495625D01*
Y-1133D01*
X495592D01*
Y-1101D01*
X495560D01*
Y-1068D01*
X495463D01*
Y-1036D01*
X495302D01*
Y-1004D01*
D02*
G37*
G36*
X488430D02*
X483978D01*
Y-1036D01*
X483914D01*
Y-1068D01*
X483881D01*
Y-1101D01*
X483849D01*
Y-1133D01*
Y-1165D01*
Y-1198D01*
X483817D01*
Y-1230D01*
Y-1262D01*
Y-1294D01*
Y-1327D01*
Y-1359D01*
Y-1391D01*
Y-1423D01*
Y-1456D01*
Y-1488D01*
Y-1520D01*
Y-1552D01*
Y-1585D01*
Y-1617D01*
Y-1649D01*
Y-1681D01*
Y-1714D01*
Y-1746D01*
Y-1778D01*
Y-1811D01*
Y-1843D01*
Y-1875D01*
Y-1907D01*
Y-1940D01*
Y-1972D01*
Y-2004D01*
Y-2036D01*
Y-2069D01*
Y-2101D01*
Y-2133D01*
Y-2165D01*
Y-2198D01*
Y-2230D01*
Y-2262D01*
Y-2294D01*
Y-2327D01*
Y-2359D01*
Y-2391D01*
Y-2424D01*
Y-2456D01*
Y-2488D01*
Y-2520D01*
Y-2553D01*
Y-2585D01*
Y-2617D01*
Y-2649D01*
Y-2682D01*
Y-2714D01*
Y-2746D01*
Y-2778D01*
Y-2811D01*
Y-2843D01*
Y-2875D01*
Y-2907D01*
Y-2940D01*
Y-2972D01*
Y-3004D01*
Y-3036D01*
Y-3069D01*
Y-3101D01*
Y-3133D01*
Y-3165D01*
Y-3198D01*
Y-3230D01*
Y-3262D01*
Y-3295D01*
Y-3327D01*
Y-3359D01*
Y-3391D01*
Y-3424D01*
Y-3456D01*
Y-3488D01*
Y-3520D01*
Y-3553D01*
Y-3585D01*
Y-3617D01*
Y-3650D01*
Y-3682D01*
Y-3714D01*
Y-3746D01*
Y-3779D01*
Y-3811D01*
Y-3843D01*
Y-3875D01*
Y-3907D01*
Y-3940D01*
Y-3972D01*
Y-4004D01*
Y-4037D01*
Y-4069D01*
Y-4101D01*
Y-4133D01*
Y-4166D01*
Y-4198D01*
Y-4230D01*
Y-4262D01*
Y-4295D01*
Y-4327D01*
Y-4359D01*
Y-4391D01*
Y-4424D01*
Y-4456D01*
Y-4488D01*
Y-4521D01*
Y-4553D01*
Y-4585D01*
Y-4617D01*
Y-4650D01*
Y-4682D01*
Y-4714D01*
Y-4746D01*
Y-4779D01*
Y-4811D01*
Y-4843D01*
Y-4875D01*
Y-4908D01*
Y-4940D01*
Y-4972D01*
Y-5004D01*
Y-5037D01*
Y-5069D01*
Y-5101D01*
Y-5133D01*
Y-5166D01*
Y-5198D01*
Y-5230D01*
Y-5263D01*
Y-5295D01*
Y-5327D01*
Y-5359D01*
Y-5392D01*
Y-5424D01*
Y-5456D01*
Y-5488D01*
Y-5521D01*
Y-5553D01*
Y-5585D01*
Y-5617D01*
Y-5650D01*
Y-5682D01*
Y-5714D01*
Y-5746D01*
Y-5779D01*
Y-5811D01*
Y-5843D01*
Y-5875D01*
Y-5908D01*
Y-5940D01*
Y-5972D01*
Y-6005D01*
Y-6037D01*
Y-6069D01*
Y-6101D01*
Y-6134D01*
Y-6166D01*
Y-6198D01*
Y-6230D01*
Y-6263D01*
Y-6295D01*
Y-6327D01*
Y-6359D01*
Y-6392D01*
Y-6424D01*
Y-6456D01*
Y-6488D01*
Y-6521D01*
Y-6553D01*
Y-6585D01*
Y-6617D01*
Y-6650D01*
Y-6682D01*
Y-6714D01*
Y-6747D01*
Y-6779D01*
Y-6811D01*
Y-6843D01*
Y-6876D01*
Y-6908D01*
Y-6940D01*
Y-6972D01*
Y-7005D01*
Y-7037D01*
Y-7069D01*
Y-7102D01*
Y-7134D01*
Y-7166D01*
Y-7198D01*
Y-7231D01*
Y-7263D01*
Y-7295D01*
Y-7327D01*
Y-7360D01*
Y-7392D01*
Y-7424D01*
Y-7456D01*
Y-7489D01*
Y-7521D01*
Y-7553D01*
Y-7585D01*
Y-7618D01*
Y-7650D01*
Y-7682D01*
Y-7714D01*
Y-7747D01*
Y-7779D01*
Y-7811D01*
X483849D01*
Y-7843D01*
X483817D01*
Y-7876D01*
X483849D01*
Y-7908D01*
Y-7940D01*
Y-7972D01*
X483881D01*
Y-8005D01*
X483946D01*
Y-8037D01*
X485527D01*
Y-8005D01*
X485559D01*
Y-7972D01*
X485591D01*
Y-7940D01*
Y-7908D01*
Y-7876D01*
X485623D01*
Y-7843D01*
Y-7811D01*
Y-7779D01*
Y-7747D01*
Y-7714D01*
Y-7682D01*
Y-7650D01*
Y-7618D01*
Y-7585D01*
Y-7553D01*
Y-7521D01*
Y-7489D01*
Y-7456D01*
Y-7424D01*
Y-7392D01*
Y-7360D01*
Y-7327D01*
Y-7295D01*
Y-7263D01*
Y-7231D01*
Y-7198D01*
Y-7166D01*
Y-7134D01*
Y-7102D01*
Y-7069D01*
Y-7037D01*
Y-7005D01*
Y-6972D01*
Y-6940D01*
Y-6908D01*
Y-6876D01*
Y-6843D01*
Y-6811D01*
Y-6779D01*
Y-6747D01*
Y-6714D01*
Y-6682D01*
Y-6650D01*
Y-6617D01*
Y-6585D01*
Y-6553D01*
Y-6521D01*
Y-6488D01*
Y-6456D01*
Y-6424D01*
Y-6392D01*
Y-6359D01*
Y-6327D01*
Y-6295D01*
Y-6263D01*
Y-6230D01*
Y-6198D01*
Y-6166D01*
Y-6134D01*
X485591D01*
Y-6101D01*
X485623D01*
Y-6069D01*
Y-6037D01*
Y-6005D01*
Y-5972D01*
Y-5940D01*
X486849D01*
Y-5972D01*
Y-6005D01*
X486882D01*
Y-6037D01*
Y-6069D01*
X486914D01*
Y-6101D01*
X486946D01*
Y-6134D01*
Y-6166D01*
X486978D01*
Y-6198D01*
Y-6230D01*
X487011D01*
Y-6263D01*
X487043D01*
Y-6295D01*
Y-6327D01*
X487075D01*
Y-6359D01*
Y-6392D01*
X487108D01*
Y-6424D01*
Y-6456D01*
X487140D01*
Y-6488D01*
X487172D01*
Y-6521D01*
Y-6553D01*
X487204D01*
Y-6585D01*
Y-6617D01*
X487236D01*
Y-6650D01*
X487269D01*
Y-6682D01*
Y-6714D01*
X487301D01*
Y-6747D01*
Y-6779D01*
X487333D01*
Y-6811D01*
X487366D01*
Y-6843D01*
Y-6876D01*
X487398D01*
Y-6908D01*
Y-6940D01*
X487430D01*
Y-6972D01*
Y-7005D01*
X487462D01*
Y-7037D01*
X487495D01*
Y-7069D01*
Y-7102D01*
X487527D01*
Y-7134D01*
Y-7166D01*
X487559D01*
Y-7198D01*
X487591D01*
Y-7231D01*
Y-7263D01*
X487624D01*
Y-7295D01*
Y-7327D01*
X487656D01*
Y-7360D01*
X487688D01*
Y-7392D01*
Y-7424D01*
X487720D01*
Y-7456D01*
Y-7489D01*
X487753D01*
Y-7521D01*
X487785D01*
Y-7553D01*
Y-7585D01*
X487817D01*
Y-7618D01*
Y-7650D01*
X487850D01*
Y-7682D01*
Y-7714D01*
X487882D01*
Y-7747D01*
X487914D01*
Y-7779D01*
Y-7811D01*
X487946D01*
Y-7843D01*
Y-7876D01*
X487979D01*
Y-7908D01*
X488011D01*
Y-7940D01*
X488043D01*
Y-7972D01*
X488075D01*
Y-8005D01*
X488140D01*
Y-8037D01*
X489947D01*
Y-8005D01*
X489979D01*
Y-7972D01*
Y-7940D01*
Y-7908D01*
Y-7876D01*
X489947D01*
Y-7843D01*
X489914D01*
Y-7811D01*
Y-7779D01*
X489882D01*
Y-7747D01*
Y-7714D01*
X489850D01*
Y-7682D01*
X489817D01*
Y-7650D01*
Y-7618D01*
X489785D01*
Y-7585D01*
Y-7553D01*
X489753D01*
Y-7521D01*
X489721D01*
Y-7489D01*
Y-7456D01*
X489688D01*
Y-7424D01*
Y-7392D01*
X489656D01*
Y-7360D01*
X489624D01*
Y-7327D01*
Y-7295D01*
X489592D01*
Y-7263D01*
Y-7231D01*
X489559D01*
Y-7198D01*
X489527D01*
Y-7166D01*
Y-7134D01*
X489495D01*
Y-7102D01*
Y-7069D01*
X489463D01*
Y-7037D01*
X489430D01*
Y-7005D01*
Y-6972D01*
X489398D01*
Y-6940D01*
Y-6908D01*
X489366D01*
Y-6876D01*
X489333D01*
Y-6843D01*
Y-6811D01*
X489301D01*
Y-6779D01*
Y-6747D01*
X489269D01*
Y-6714D01*
X489237D01*
Y-6682D01*
Y-6650D01*
X489205D01*
Y-6617D01*
Y-6585D01*
X489172D01*
Y-6553D01*
X489140D01*
Y-6521D01*
Y-6488D01*
X489108D01*
Y-6456D01*
Y-6424D01*
X489076D01*
Y-6392D01*
X489043D01*
Y-6359D01*
Y-6327D01*
X489011D01*
Y-6295D01*
Y-6263D01*
X488979D01*
Y-6230D01*
X488946D01*
Y-6198D01*
Y-6166D01*
X488914D01*
Y-6134D01*
Y-6101D01*
X488882D01*
Y-6069D01*
Y-6037D01*
X488850D01*
Y-6005D01*
X488817D01*
Y-5972D01*
Y-5940D01*
X488785D01*
Y-5908D01*
Y-5875D01*
X488753D01*
Y-5843D01*
X488721D01*
Y-5811D01*
Y-5779D01*
X488753D01*
Y-5746D01*
X488785D01*
Y-5714D01*
X488817D01*
Y-5682D01*
X488850D01*
Y-5650D01*
X488882D01*
Y-5617D01*
X488914D01*
Y-5585D01*
X488946D01*
Y-5553D01*
X488979D01*
Y-5521D01*
X489011D01*
Y-5488D01*
X489043D01*
Y-5456D01*
X489076D01*
Y-5424D01*
X489108D01*
Y-5392D01*
X489140D01*
Y-5359D01*
X489172D01*
Y-5327D01*
X489205D01*
Y-5295D01*
X489237D01*
Y-5263D01*
X489269D01*
Y-5230D01*
X489301D01*
Y-5198D01*
X489333D01*
Y-5166D01*
X489366D01*
Y-5133D01*
X489398D01*
Y-5101D01*
X489430D01*
Y-5069D01*
X489463D01*
Y-5037D01*
Y-5004D01*
X489495D01*
Y-4972D01*
X489527D01*
Y-4940D01*
X489559D01*
Y-4908D01*
X489592D01*
Y-4875D01*
X489624D01*
Y-4843D01*
X489656D01*
Y-4811D01*
Y-4779D01*
X489688D01*
Y-4746D01*
Y-4714D01*
X489721D01*
Y-4682D01*
Y-4650D01*
Y-4617D01*
Y-4585D01*
Y-4553D01*
Y-4521D01*
Y-4488D01*
Y-4456D01*
Y-4424D01*
Y-4391D01*
Y-4359D01*
Y-4327D01*
Y-4295D01*
Y-4262D01*
Y-4230D01*
Y-4198D01*
Y-4166D01*
Y-4133D01*
Y-4101D01*
Y-4069D01*
Y-4037D01*
Y-4004D01*
Y-3972D01*
Y-3940D01*
Y-3907D01*
Y-3875D01*
Y-3843D01*
Y-3811D01*
Y-3779D01*
Y-3746D01*
Y-3714D01*
Y-3682D01*
Y-3650D01*
Y-3617D01*
Y-3585D01*
Y-3553D01*
Y-3520D01*
Y-3488D01*
Y-3456D01*
Y-3424D01*
Y-3391D01*
Y-3359D01*
Y-3327D01*
Y-3295D01*
Y-3262D01*
Y-3230D01*
Y-3198D01*
Y-3165D01*
Y-3133D01*
Y-3101D01*
Y-3069D01*
Y-3036D01*
Y-3004D01*
Y-2972D01*
Y-2940D01*
Y-2907D01*
Y-2875D01*
Y-2843D01*
Y-2811D01*
Y-2778D01*
Y-2746D01*
Y-2714D01*
Y-2682D01*
Y-2649D01*
Y-2617D01*
Y-2585D01*
Y-2553D01*
Y-2520D01*
Y-2488D01*
Y-2456D01*
Y-2424D01*
Y-2391D01*
Y-2359D01*
Y-2327D01*
Y-2294D01*
Y-2262D01*
Y-2230D01*
Y-2198D01*
Y-2165D01*
X489688D01*
Y-2133D01*
Y-2101D01*
Y-2069D01*
X489656D01*
Y-2036D01*
Y-2004D01*
X489624D01*
Y-1972D01*
X489592D01*
Y-1940D01*
X489559D01*
Y-1907D01*
X489527D01*
Y-1875D01*
X489495D01*
Y-1843D01*
X489463D01*
Y-1811D01*
X489430D01*
Y-1778D01*
X489398D01*
Y-1746D01*
X489366D01*
Y-1714D01*
X489333D01*
Y-1681D01*
X489301D01*
Y-1649D01*
X489269D01*
Y-1617D01*
X489237D01*
Y-1585D01*
X489205D01*
Y-1552D01*
X489172D01*
Y-1520D01*
X489140D01*
Y-1488D01*
X489108D01*
Y-1456D01*
X489076D01*
Y-1423D01*
X489043D01*
Y-1391D01*
X489011D01*
Y-1359D01*
X488979D01*
Y-1327D01*
X488946D01*
Y-1294D01*
X488914D01*
Y-1262D01*
X488882D01*
Y-1230D01*
X488850D01*
Y-1198D01*
X488817D01*
Y-1165D01*
X488785D01*
Y-1133D01*
X488753D01*
Y-1101D01*
X488688D01*
Y-1068D01*
X488591D01*
Y-1036D01*
X488430D01*
Y-1004D01*
D02*
G37*
G36*
X468105Y-1036D02*
X467718D01*
Y-1068D01*
Y-1101D01*
Y-1133D01*
Y-1165D01*
Y-1198D01*
Y-1230D01*
Y-1262D01*
Y-1294D01*
Y-1327D01*
Y-1359D01*
Y-1391D01*
X467750D01*
Y-1423D01*
Y-1456D01*
Y-1488D01*
Y-1520D01*
Y-1552D01*
Y-1585D01*
Y-1617D01*
Y-1649D01*
Y-1681D01*
Y-1714D01*
Y-1746D01*
X467783D01*
Y-1778D01*
X467750D01*
Y-1811D01*
X467783D01*
Y-1843D01*
Y-1875D01*
Y-1907D01*
Y-1940D01*
Y-1972D01*
Y-2004D01*
Y-2036D01*
Y-2069D01*
Y-2101D01*
Y-2133D01*
X467815D01*
Y-2165D01*
Y-2198D01*
Y-2230D01*
Y-2262D01*
Y-2294D01*
Y-2327D01*
Y-2359D01*
Y-2391D01*
X467847D01*
Y-2424D01*
Y-2456D01*
Y-2488D01*
Y-2520D01*
Y-2553D01*
Y-2585D01*
Y-2617D01*
X467879D01*
Y-2649D01*
Y-2682D01*
Y-2714D01*
Y-2746D01*
Y-2778D01*
Y-2811D01*
X467912D01*
Y-2843D01*
Y-2875D01*
Y-2907D01*
Y-2940D01*
Y-2972D01*
X467944D01*
Y-3004D01*
Y-3036D01*
Y-3069D01*
Y-3101D01*
Y-3133D01*
X467976D01*
Y-3165D01*
Y-3198D01*
Y-3230D01*
Y-3262D01*
Y-3295D01*
X468009D01*
Y-3327D01*
Y-3359D01*
Y-3391D01*
Y-3424D01*
Y-3456D01*
X468041D01*
Y-3488D01*
Y-3520D01*
Y-3553D01*
Y-3585D01*
X468073D01*
Y-3617D01*
Y-3650D01*
Y-3682D01*
Y-3714D01*
X468105D01*
Y-3746D01*
Y-3779D01*
Y-3811D01*
Y-3843D01*
X468138D01*
Y-3875D01*
Y-3907D01*
Y-3940D01*
Y-3972D01*
X468170D01*
Y-4004D01*
Y-4037D01*
Y-4069D01*
X468202D01*
Y-4101D01*
Y-4133D01*
Y-4166D01*
Y-4198D01*
X468234D01*
Y-4230D01*
Y-4262D01*
Y-4295D01*
X468267D01*
Y-4327D01*
Y-4359D01*
Y-4391D01*
X468299D01*
Y-4424D01*
Y-4456D01*
Y-4488D01*
X468331D01*
Y-4521D01*
Y-4553D01*
Y-4585D01*
X468363D01*
Y-4617D01*
Y-4650D01*
Y-4682D01*
X468396D01*
Y-4714D01*
Y-4746D01*
Y-4779D01*
X468428D01*
Y-4811D01*
Y-4843D01*
Y-4875D01*
X468460D01*
Y-4908D01*
Y-4940D01*
Y-4972D01*
X468492D01*
Y-5004D01*
Y-5037D01*
Y-5069D01*
X468525D01*
Y-5101D01*
Y-5133D01*
X468557D01*
Y-5166D01*
Y-5198D01*
Y-5230D01*
X468589D01*
Y-5263D01*
Y-5295D01*
X468621D01*
Y-5327D01*
Y-5359D01*
Y-5392D01*
X468654D01*
Y-5424D01*
Y-5456D01*
X468686D01*
Y-5488D01*
Y-5521D01*
Y-5553D01*
X468718D01*
Y-5585D01*
Y-5617D01*
X468750D01*
Y-5650D01*
Y-5682D01*
X468783D01*
Y-5714D01*
Y-5746D01*
Y-5779D01*
X468815D01*
Y-5811D01*
Y-5843D01*
X468847D01*
Y-5875D01*
Y-5908D01*
X468880D01*
Y-5940D01*
Y-5972D01*
X468912D01*
Y-6005D01*
Y-6037D01*
X468944D01*
Y-6069D01*
Y-6101D01*
X468976D01*
Y-6134D01*
Y-6166D01*
X469009D01*
Y-6198D01*
Y-6230D01*
X469041D01*
Y-6263D01*
Y-6295D01*
X469073D01*
Y-6327D01*
Y-6359D01*
X469105D01*
Y-6392D01*
Y-6424D01*
X469138D01*
Y-6456D01*
Y-6488D01*
X469170D01*
Y-6521D01*
Y-6553D01*
X469202D01*
Y-6585D01*
Y-6617D01*
X469235D01*
Y-6650D01*
X469267D01*
Y-6682D01*
Y-6714D01*
X469299D01*
Y-6747D01*
Y-6779D01*
X469331D01*
Y-6811D01*
Y-6843D01*
X469363D01*
Y-6876D01*
Y-6908D01*
X469396D01*
Y-6940D01*
X469428D01*
Y-6972D01*
Y-7005D01*
X469460D01*
Y-7037D01*
Y-7069D01*
X469492D01*
Y-7102D01*
Y-7134D01*
X469525D01*
Y-7166D01*
X469557D01*
Y-7198D01*
Y-7231D01*
X469589D01*
Y-7263D01*
X469622D01*
Y-7295D01*
Y-7327D01*
X469654D01*
Y-7360D01*
Y-7392D01*
X469686D01*
Y-7424D01*
X469718D01*
Y-7456D01*
Y-7489D01*
X469751D01*
Y-7521D01*
X469783D01*
Y-7553D01*
Y-7585D01*
X469815D01*
Y-7618D01*
X469847D01*
Y-7650D01*
Y-7682D01*
X469880D01*
Y-7714D01*
X469912D01*
Y-7747D01*
Y-7779D01*
X469944D01*
Y-7811D01*
X469977D01*
Y-7843D01*
X470009D01*
Y-7876D01*
Y-7908D01*
X470041D01*
Y-7940D01*
X470073D01*
Y-7972D01*
Y-8005D01*
X470106D01*
Y-8037D01*
X470138D01*
Y-8069D01*
X470170D01*
Y-8102D01*
Y-8134D01*
X470202D01*
Y-8166D01*
X470235D01*
Y-8198D01*
X470267D01*
Y-8231D01*
Y-8263D01*
X470299D01*
Y-8295D01*
X470331D01*
Y-8327D01*
X470364D01*
Y-8360D01*
X470396D01*
Y-8392D01*
Y-8424D01*
X470428D01*
Y-8456D01*
X470460D01*
Y-8489D01*
X470493D01*
Y-8521D01*
X470525D01*
Y-8553D01*
Y-8585D01*
X470557D01*
Y-8618D01*
X470589D01*
Y-8650D01*
X470622D01*
Y-8682D01*
X470654D01*
Y-8715D01*
Y-8747D01*
X470686D01*
Y-8779D01*
X470718D01*
Y-8811D01*
X470751D01*
Y-8844D01*
X470783D01*
Y-8876D01*
X470815D01*
Y-8908D01*
X470848D01*
Y-8940D01*
X470880D01*
Y-8973D01*
Y-9005D01*
X470912D01*
Y-9037D01*
X470944D01*
Y-9069D01*
X470977D01*
Y-9102D01*
X471009D01*
Y-9134D01*
X471041D01*
Y-9166D01*
X471073D01*
Y-9199D01*
X471106D01*
Y-9231D01*
X471138D01*
Y-9263D01*
X471170D01*
Y-9295D01*
X471202D01*
Y-9328D01*
X471235D01*
Y-9360D01*
X471267D01*
Y-9392D01*
X471299D01*
Y-9424D01*
X471332D01*
Y-9457D01*
X471364D01*
Y-9489D01*
X471396D01*
Y-9521D01*
X471428D01*
Y-9553D01*
X471460D01*
Y-9586D01*
X471493D01*
Y-9618D01*
X471525D01*
Y-9650D01*
X471557D01*
Y-9682D01*
X471590D01*
Y-9715D01*
X471622D01*
Y-9747D01*
X471654D01*
Y-9779D01*
X471686D01*
Y-9811D01*
X471719D01*
Y-9844D01*
X471751D01*
Y-9876D01*
X471783D01*
Y-9908D01*
X471815D01*
Y-9940D01*
X471848D01*
Y-9973D01*
X471912D01*
Y-10005D01*
X471944D01*
Y-10037D01*
X471977D01*
Y-10069D01*
X472009D01*
Y-10102D01*
X472041D01*
Y-10134D01*
X472074D01*
Y-10166D01*
X472106D01*
Y-10199D01*
X472170D01*
Y-10231D01*
X472202D01*
Y-10263D01*
X472235D01*
Y-10295D01*
X472267D01*
Y-10328D01*
X472299D01*
Y-10360D01*
X472364D01*
Y-10392D01*
X472396D01*
Y-10424D01*
X472428D01*
Y-10457D01*
X472461D01*
Y-10489D01*
X472525D01*
Y-10521D01*
X472557D01*
Y-10554D01*
X472590D01*
Y-10586D01*
X472654D01*
Y-10618D01*
X472686D01*
Y-10650D01*
X472719D01*
Y-10683D01*
X472783D01*
Y-10715D01*
X472816D01*
Y-10747D01*
X472848D01*
Y-10779D01*
X472912D01*
Y-10812D01*
X472944D01*
Y-10844D01*
X473009D01*
Y-10876D01*
X473041D01*
Y-10908D01*
X473074D01*
Y-10941D01*
X473138D01*
Y-10973D01*
X473170D01*
Y-11005D01*
X473235D01*
Y-11037D01*
X473267D01*
Y-11070D01*
X473332D01*
Y-11102D01*
X473364D01*
Y-11134D01*
X473428D01*
Y-11167D01*
X473461D01*
Y-11199D01*
X473525D01*
Y-11231D01*
X473590D01*
Y-11263D01*
X473622D01*
Y-11295D01*
X473687D01*
Y-11328D01*
X473719D01*
Y-11360D01*
X473783D01*
Y-11392D01*
X473848D01*
Y-11425D01*
X473880D01*
Y-11457D01*
X473945D01*
Y-11489D01*
X474009D01*
Y-11521D01*
X474074D01*
Y-11554D01*
X474106D01*
Y-11586D01*
X474170D01*
Y-11618D01*
X474235D01*
Y-11650D01*
X474299D01*
Y-11683D01*
X474364D01*
Y-11715D01*
X474429D01*
Y-11747D01*
X474493D01*
Y-11779D01*
X474558D01*
Y-11812D01*
X474622D01*
Y-11844D01*
X474687D01*
Y-11876D01*
X474751D01*
Y-11908D01*
X474816D01*
Y-11941D01*
X474880D01*
Y-11973D01*
X474945D01*
Y-12005D01*
X475009D01*
Y-12037D01*
X475074D01*
Y-12070D01*
X475171D01*
Y-12102D01*
X475235D01*
Y-12134D01*
X475300D01*
Y-12167D01*
X475396D01*
Y-12199D01*
X475461D01*
Y-12231D01*
X475558D01*
Y-12263D01*
X475622D01*
Y-12296D01*
X475719D01*
Y-12328D01*
X475784D01*
Y-12360D01*
X475880D01*
Y-12392D01*
X475977D01*
Y-12425D01*
X476074D01*
Y-12457D01*
X476138D01*
Y-12489D01*
X476235D01*
Y-12521D01*
X476332D01*
Y-12554D01*
X476461D01*
Y-12586D01*
X476558D01*
Y-12618D01*
X476655D01*
Y-12651D01*
X476784D01*
Y-12683D01*
X476881D01*
Y-12715D01*
X477009D01*
Y-12747D01*
X477139D01*
Y-12780D01*
X477268D01*
Y-12812D01*
X477397D01*
Y-12844D01*
X477558D01*
Y-12876D01*
X477687D01*
Y-12909D01*
X477848D01*
Y-12941D01*
X478042D01*
Y-12973D01*
X478235D01*
Y-13005D01*
X478461D01*
Y-13038D01*
X478687D01*
Y-13070D01*
X479010D01*
Y-13102D01*
X479397D01*
Y-13134D01*
X480945D01*
Y-13102D01*
X481365D01*
Y-13070D01*
X481655D01*
Y-13038D01*
X481913D01*
Y-13005D01*
X482139D01*
Y-12973D01*
X482333D01*
Y-12941D01*
X482494D01*
Y-12909D01*
X482688D01*
Y-12876D01*
X482817D01*
Y-12844D01*
X482946D01*
Y-12812D01*
X483107D01*
Y-12780D01*
X483236D01*
Y-12747D01*
X483365D01*
Y-12715D01*
X483494D01*
Y-12683D01*
X483591D01*
Y-12651D01*
X483720D01*
Y-12618D01*
X483817D01*
Y-12586D01*
X483914D01*
Y-12554D01*
X484010D01*
Y-12521D01*
X484107D01*
Y-12489D01*
X484204D01*
Y-12457D01*
X484301D01*
Y-12425D01*
X484398D01*
Y-12392D01*
X484494D01*
Y-12360D01*
X484591D01*
Y-12328D01*
X484656D01*
Y-12296D01*
X484752D01*
Y-12263D01*
X484817D01*
Y-12231D01*
X484914D01*
Y-12199D01*
X484978D01*
Y-12167D01*
X485075D01*
Y-12134D01*
X485140D01*
Y-12102D01*
X485204D01*
Y-12070D01*
X485301D01*
Y-12037D01*
X485365D01*
Y-12005D01*
X485430D01*
Y-11973D01*
X485494D01*
Y-11941D01*
X485559D01*
Y-11908D01*
X485623D01*
Y-11876D01*
X485688D01*
Y-11844D01*
X485752D01*
Y-11812D01*
X485817D01*
Y-11779D01*
X485882D01*
Y-11747D01*
X485946D01*
Y-11715D01*
X486011D01*
Y-11683D01*
X486075D01*
Y-11650D01*
X486140D01*
Y-11618D01*
X486204D01*
Y-11586D01*
X486236D01*
Y-11554D01*
X486301D01*
Y-11521D01*
X486366D01*
Y-11489D01*
X486430D01*
Y-11457D01*
X486462D01*
Y-11425D01*
X486527D01*
Y-11392D01*
X486591D01*
Y-11360D01*
X486623D01*
Y-11328D01*
X486688D01*
Y-11295D01*
X486753D01*
Y-11263D01*
X486785D01*
Y-11231D01*
X486849D01*
Y-11199D01*
X486882D01*
Y-11167D01*
X486946D01*
Y-11134D01*
X487011D01*
Y-11102D01*
X487043D01*
Y-11070D01*
X487108D01*
Y-11037D01*
X487140D01*
Y-11005D01*
X487204D01*
Y-10973D01*
X487236D01*
Y-10941D01*
X487269D01*
Y-10908D01*
X487333D01*
Y-10876D01*
X487366D01*
Y-10844D01*
X487430D01*
Y-10812D01*
X487462D01*
Y-10779D01*
X487527D01*
Y-10747D01*
X487559D01*
Y-10715D01*
X487591D01*
Y-10683D01*
X487656D01*
Y-10650D01*
X487688D01*
Y-10618D01*
X487720D01*
Y-10586D01*
X487785D01*
Y-10554D01*
X487817D01*
Y-10521D01*
X487850D01*
Y-10489D01*
X487882D01*
Y-10457D01*
X487946D01*
Y-10424D01*
X487979D01*
Y-10392D01*
X488011D01*
Y-10360D01*
X488043D01*
Y-10328D01*
X488108D01*
Y-10295D01*
X488140D01*
Y-10263D01*
X488172D01*
Y-10231D01*
X488204D01*
Y-10199D01*
X488237D01*
Y-10166D01*
X488301D01*
Y-10134D01*
X488333D01*
Y-10102D01*
X488366D01*
Y-10069D01*
X488398D01*
Y-10037D01*
X488430D01*
Y-10005D01*
X488462D01*
Y-9973D01*
X488495D01*
Y-9940D01*
X488559D01*
Y-9908D01*
X488591D01*
Y-9876D01*
X488624D01*
Y-9844D01*
X488656D01*
Y-9811D01*
X488688D01*
Y-9779D01*
X488721D01*
Y-9747D01*
X488753D01*
Y-9715D01*
X488785D01*
Y-9682D01*
X488817D01*
Y-9650D01*
X488850D01*
Y-9618D01*
X488882D01*
Y-9586D01*
X488914D01*
Y-9553D01*
X488946D01*
Y-9521D01*
X488979D01*
Y-9489D01*
X489011D01*
Y-9457D01*
X489043D01*
Y-9424D01*
X489076D01*
Y-9392D01*
X489108D01*
Y-9360D01*
X489140D01*
Y-9328D01*
X489172D01*
Y-9295D01*
X489205D01*
Y-9263D01*
X489237D01*
Y-9231D01*
X489269D01*
Y-9199D01*
X489301D01*
Y-9166D01*
X489333D01*
Y-9134D01*
X489366D01*
Y-9102D01*
X489398D01*
Y-9069D01*
X489430D01*
Y-9037D01*
X489463D01*
Y-9005D01*
Y-8973D01*
X489495D01*
Y-8940D01*
X489527D01*
Y-8908D01*
X489559D01*
Y-8876D01*
X489592D01*
Y-8844D01*
X489624D01*
Y-8811D01*
X489656D01*
Y-8779D01*
X489688D01*
Y-8747D01*
Y-8715D01*
X489721D01*
Y-8682D01*
X489205D01*
Y-8715D01*
X489172D01*
Y-8747D01*
X489140D01*
Y-8779D01*
Y-8811D01*
X489108D01*
Y-8844D01*
X489076D01*
Y-8876D01*
X489043D01*
Y-8908D01*
X489011D01*
Y-8940D01*
X488979D01*
Y-8973D01*
X488946D01*
Y-9005D01*
X488914D01*
Y-9037D01*
X488882D01*
Y-9069D01*
X488850D01*
Y-9102D01*
X488817D01*
Y-9134D01*
X488785D01*
Y-9166D01*
X488753D01*
Y-9199D01*
X488721D01*
Y-9231D01*
X488688D01*
Y-9263D01*
X488656D01*
Y-9295D01*
X488624D01*
Y-9328D01*
X488591D01*
Y-9360D01*
X488559D01*
Y-9392D01*
X488527D01*
Y-9424D01*
X488495D01*
Y-9457D01*
X488462D01*
Y-9489D01*
X488430D01*
Y-9521D01*
X488398D01*
Y-9553D01*
X488366D01*
Y-9586D01*
X488333D01*
Y-9618D01*
X488269D01*
Y-9650D01*
X488237D01*
Y-9682D01*
X488204D01*
Y-9715D01*
X488172D01*
Y-9747D01*
X488140D01*
Y-9779D01*
X488108D01*
Y-9811D01*
X488075D01*
Y-9844D01*
X488011D01*
Y-9876D01*
X487979D01*
Y-9908D01*
X487946D01*
Y-9940D01*
X487914D01*
Y-9973D01*
X487882D01*
Y-10005D01*
X487817D01*
Y-10037D01*
X487785D01*
Y-10069D01*
X487753D01*
Y-10102D01*
X487720D01*
Y-10134D01*
X487656D01*
Y-10166D01*
X487624D01*
Y-10199D01*
X487591D01*
Y-10231D01*
X487559D01*
Y-10263D01*
X487495D01*
Y-10295D01*
X487462D01*
Y-10328D01*
X487430D01*
Y-10360D01*
X487366D01*
Y-10392D01*
X487333D01*
Y-10424D01*
X487301D01*
Y-10457D01*
X487236D01*
Y-10489D01*
X487204D01*
Y-10521D01*
X487140D01*
Y-10554D01*
X487108D01*
Y-10586D01*
X487075D01*
Y-10618D01*
X487011D01*
Y-10650D01*
X486978D01*
Y-10683D01*
X486914D01*
Y-10715D01*
X486882D01*
Y-10747D01*
X486817D01*
Y-10779D01*
X486785D01*
Y-10812D01*
X486720D01*
Y-10844D01*
X486688D01*
Y-10876D01*
X486623D01*
Y-10908D01*
X486559D01*
Y-10941D01*
X486527D01*
Y-10973D01*
X486462D01*
Y-11005D01*
X486398D01*
Y-11037D01*
X486366D01*
Y-11070D01*
X486301D01*
Y-11102D01*
X486236D01*
Y-11134D01*
X486204D01*
Y-11167D01*
X486140D01*
Y-11199D01*
X486075D01*
Y-11231D01*
X486011D01*
Y-11263D01*
X485978D01*
Y-11295D01*
X485914D01*
Y-11328D01*
X485849D01*
Y-11360D01*
X485785D01*
Y-11392D01*
X485720D01*
Y-11425D01*
X485656D01*
Y-11457D01*
X485591D01*
Y-11489D01*
X485527D01*
Y-11521D01*
X485462D01*
Y-11554D01*
X485398D01*
Y-11586D01*
X485333D01*
Y-11618D01*
X485269D01*
Y-11650D01*
X485204D01*
Y-11683D01*
X485140D01*
Y-11715D01*
X485043D01*
Y-11747D01*
X484978D01*
Y-11779D01*
X484881D01*
Y-11812D01*
X484817D01*
Y-11844D01*
X484752D01*
Y-11876D01*
X484656D01*
Y-11908D01*
X484591D01*
Y-11941D01*
X484494D01*
Y-11973D01*
X484398D01*
Y-12005D01*
X484333D01*
Y-12037D01*
X484236D01*
Y-12070D01*
X484139D01*
Y-12102D01*
X484043D01*
Y-12134D01*
X483946D01*
Y-12167D01*
X483849D01*
Y-12199D01*
X483752D01*
Y-12231D01*
X483656D01*
Y-12263D01*
X483526D01*
Y-12296D01*
X483430D01*
Y-12328D01*
X483301D01*
Y-12360D01*
X483172D01*
Y-12392D01*
X483042D01*
Y-12425D01*
X482913D01*
Y-12457D01*
X482752D01*
Y-12489D01*
X482623D01*
Y-12521D01*
X482462D01*
Y-12554D01*
X482268D01*
Y-12586D01*
X482075D01*
Y-12618D01*
X481849D01*
Y-12651D01*
X481655D01*
Y-12683D01*
X481268D01*
Y-12715D01*
X480913D01*
Y-12747D01*
X480881D01*
Y-12715D01*
X480816D01*
Y-12747D01*
X479558D01*
Y-12715D01*
X479074D01*
Y-12683D01*
X478784D01*
Y-12651D01*
X478526D01*
Y-12618D01*
X478300D01*
Y-12586D01*
X478106D01*
Y-12554D01*
X477913D01*
Y-12521D01*
X477752D01*
Y-12489D01*
X477590D01*
Y-12457D01*
X477461D01*
Y-12425D01*
X477332D01*
Y-12392D01*
X477203D01*
Y-12360D01*
X477074D01*
Y-12328D01*
X476945D01*
Y-12296D01*
X476848D01*
Y-12263D01*
X476719D01*
Y-12231D01*
X476622D01*
Y-12199D01*
X476526D01*
Y-12167D01*
X476429D01*
Y-12134D01*
X476332D01*
Y-12102D01*
X476235D01*
Y-12070D01*
X476138D01*
Y-12037D01*
X476042D01*
Y-12005D01*
X475945D01*
Y-11973D01*
X475880D01*
Y-11941D01*
X475784D01*
Y-11908D01*
X475719D01*
Y-11876D01*
X475622D01*
Y-11844D01*
X475558D01*
Y-11812D01*
X475461D01*
Y-11779D01*
X475396D01*
Y-11747D01*
X475332D01*
Y-11715D01*
X475267D01*
Y-11683D01*
X475171D01*
Y-11650D01*
X475106D01*
Y-11618D01*
X475042D01*
Y-11586D01*
X474977D01*
Y-11554D01*
X474913D01*
Y-11521D01*
X474848D01*
Y-11489D01*
X474784D01*
Y-11457D01*
X474719D01*
Y-11425D01*
X474654D01*
Y-11392D01*
X474590D01*
Y-11360D01*
X474525D01*
Y-11328D01*
X474461D01*
Y-11295D01*
X474396D01*
Y-11263D01*
X474364D01*
Y-11231D01*
X474299D01*
Y-11199D01*
X474235D01*
Y-11167D01*
X474170D01*
Y-11134D01*
X474106D01*
Y-11102D01*
X474074D01*
Y-11070D01*
X474009D01*
Y-11037D01*
X473945D01*
Y-11005D01*
X473912D01*
Y-10973D01*
X473848D01*
Y-10941D01*
X473816D01*
Y-10908D01*
X473751D01*
Y-10876D01*
X473687D01*
Y-10844D01*
X473654D01*
Y-10812D01*
X473590D01*
Y-10779D01*
X473558D01*
Y-10747D01*
X473493D01*
Y-10715D01*
X473461D01*
Y-10683D01*
X473396D01*
Y-10650D01*
X473364D01*
Y-10618D01*
X473299D01*
Y-10586D01*
X473267D01*
Y-10554D01*
X473203D01*
Y-10521D01*
X473170D01*
Y-10489D01*
X473138D01*
Y-10457D01*
X473074D01*
Y-10424D01*
X473041D01*
Y-10392D01*
X473009D01*
Y-10360D01*
X472944D01*
Y-10328D01*
X472912D01*
Y-10295D01*
X472880D01*
Y-10263D01*
X472816D01*
Y-10231D01*
X472783D01*
Y-10199D01*
X472751D01*
Y-10166D01*
X472686D01*
Y-10134D01*
X472654D01*
Y-10102D01*
X472622D01*
Y-10069D01*
X472590D01*
Y-10037D01*
X472525D01*
Y-10005D01*
X472493D01*
Y-9973D01*
X472461D01*
Y-9940D01*
X472428D01*
Y-9908D01*
X472396D01*
Y-9876D01*
X472332D01*
Y-9844D01*
X472299D01*
Y-9811D01*
X472267D01*
Y-9779D01*
X472235D01*
Y-9747D01*
X472202D01*
Y-9715D01*
X472170D01*
Y-9682D01*
X472138D01*
Y-9650D01*
X472074D01*
Y-9618D01*
X472041D01*
Y-9586D01*
X472009D01*
Y-9553D01*
X471977D01*
Y-9521D01*
X471944D01*
Y-9489D01*
X471912D01*
Y-9457D01*
X471880D01*
Y-9424D01*
X471848D01*
Y-9392D01*
X471815D01*
Y-9360D01*
X471783D01*
Y-9328D01*
X471751D01*
Y-9295D01*
X471719D01*
Y-9263D01*
X471686D01*
Y-9231D01*
X471654D01*
Y-9199D01*
X471622D01*
Y-9166D01*
X471590D01*
Y-9134D01*
X471557D01*
Y-9102D01*
X471525D01*
Y-9069D01*
X471493D01*
Y-9037D01*
X471460D01*
Y-9005D01*
X471428D01*
Y-8973D01*
X471396D01*
Y-8940D01*
X471364D01*
Y-8908D01*
X471332D01*
Y-8876D01*
X471299D01*
Y-8844D01*
X471267D01*
Y-8811D01*
X471235D01*
Y-8779D01*
X471202D01*
Y-8747D01*
Y-8715D01*
X471170D01*
Y-8682D01*
X471138D01*
Y-8650D01*
X471106D01*
Y-8618D01*
X471073D01*
Y-8585D01*
X471041D01*
Y-8553D01*
X471009D01*
Y-8521D01*
X470977D01*
Y-8489D01*
Y-8456D01*
X470944D01*
Y-8424D01*
X470912D01*
Y-8392D01*
X470880D01*
Y-8360D01*
X470848D01*
Y-8327D01*
X470815D01*
Y-8295D01*
Y-8263D01*
X470783D01*
Y-8231D01*
X470751D01*
Y-8198D01*
X470718D01*
Y-8166D01*
X470686D01*
Y-8134D01*
Y-8102D01*
X470654D01*
Y-8069D01*
X470622D01*
Y-8037D01*
X470589D01*
Y-8005D01*
Y-7972D01*
X470557D01*
Y-7940D01*
X470525D01*
Y-7908D01*
X470493D01*
Y-7876D01*
Y-7843D01*
X470460D01*
Y-7811D01*
X470428D01*
Y-7779D01*
X470396D01*
Y-7747D01*
Y-7714D01*
X470364D01*
Y-7682D01*
X470331D01*
Y-7650D01*
X470299D01*
Y-7618D01*
Y-7585D01*
X470267D01*
Y-7553D01*
X470235D01*
Y-7521D01*
Y-7489D01*
X470202D01*
Y-7456D01*
X470170D01*
Y-7424D01*
Y-7392D01*
X470138D01*
Y-7360D01*
X470106D01*
Y-7327D01*
Y-7295D01*
X470073D01*
Y-7263D01*
X470041D01*
Y-7231D01*
Y-7198D01*
X470009D01*
Y-7166D01*
X469977D01*
Y-7134D01*
Y-7102D01*
X469944D01*
Y-7069D01*
Y-7037D01*
X469912D01*
Y-7005D01*
X469880D01*
Y-6972D01*
Y-6940D01*
X469847D01*
Y-6908D01*
X469815D01*
Y-6876D01*
Y-6843D01*
X469783D01*
Y-6811D01*
Y-6779D01*
X469751D01*
Y-6747D01*
Y-6714D01*
X469718D01*
Y-6682D01*
X469686D01*
Y-6650D01*
Y-6617D01*
X469654D01*
Y-6585D01*
Y-6553D01*
X469622D01*
Y-6521D01*
Y-6488D01*
X469589D01*
Y-6456D01*
X469557D01*
Y-6424D01*
Y-6392D01*
X469525D01*
Y-6359D01*
Y-6327D01*
X469492D01*
Y-6295D01*
Y-6263D01*
X469460D01*
Y-6230D01*
Y-6198D01*
X469428D01*
Y-6166D01*
Y-6134D01*
X469396D01*
Y-6101D01*
Y-6069D01*
X469363D01*
Y-6037D01*
Y-6005D01*
X469331D01*
Y-5972D01*
Y-5940D01*
X469299D01*
Y-5908D01*
Y-5875D01*
X469267D01*
Y-5843D01*
Y-5811D01*
X469235D01*
Y-5779D01*
Y-5746D01*
X469202D01*
Y-5714D01*
Y-5682D01*
X469170D01*
Y-5650D01*
Y-5617D01*
Y-5585D01*
X469138D01*
Y-5553D01*
Y-5521D01*
X469105D01*
Y-5488D01*
Y-5456D01*
X469073D01*
Y-5424D01*
Y-5392D01*
Y-5359D01*
X469041D01*
Y-5327D01*
Y-5295D01*
X469009D01*
Y-5263D01*
Y-5230D01*
X468976D01*
Y-5198D01*
Y-5166D01*
Y-5133D01*
X468944D01*
Y-5101D01*
Y-5069D01*
X468912D01*
Y-5037D01*
Y-5004D01*
Y-4972D01*
X468880D01*
Y-4940D01*
Y-4908D01*
Y-4875D01*
X468847D01*
Y-4843D01*
Y-4811D01*
X468815D01*
Y-4779D01*
Y-4746D01*
Y-4714D01*
X468783D01*
Y-4682D01*
Y-4650D01*
Y-4617D01*
X468750D01*
Y-4585D01*
Y-4553D01*
Y-4521D01*
X468718D01*
Y-4488D01*
Y-4456D01*
Y-4424D01*
X468686D01*
Y-4391D01*
Y-4359D01*
Y-4327D01*
X468654D01*
Y-4295D01*
Y-4262D01*
Y-4230D01*
X468621D01*
Y-4198D01*
Y-4166D01*
Y-4133D01*
X468589D01*
Y-4101D01*
Y-4069D01*
Y-4037D01*
Y-4004D01*
X468557D01*
Y-3972D01*
Y-3940D01*
Y-3907D01*
X468525D01*
Y-3875D01*
Y-3843D01*
Y-3811D01*
Y-3779D01*
X468492D01*
Y-3746D01*
Y-3714D01*
Y-3682D01*
Y-3650D01*
X468460D01*
Y-3617D01*
Y-3585D01*
Y-3553D01*
Y-3520D01*
X468428D01*
Y-3488D01*
Y-3456D01*
Y-3424D01*
Y-3391D01*
X468396D01*
Y-3359D01*
Y-3327D01*
Y-3295D01*
Y-3262D01*
Y-3230D01*
X468363D01*
Y-3198D01*
Y-3165D01*
Y-3133D01*
Y-3101D01*
Y-3069D01*
X468331D01*
Y-3036D01*
Y-3004D01*
Y-2972D01*
Y-2940D01*
Y-2907D01*
X468299D01*
Y-2875D01*
Y-2843D01*
Y-2811D01*
Y-2778D01*
Y-2746D01*
X468267D01*
Y-2714D01*
Y-2682D01*
Y-2649D01*
Y-2617D01*
Y-2585D01*
Y-2553D01*
X468234D01*
Y-2520D01*
Y-2488D01*
Y-2456D01*
Y-2424D01*
Y-2391D01*
Y-2359D01*
Y-2327D01*
X468202D01*
Y-2294D01*
Y-2262D01*
Y-2230D01*
Y-2198D01*
Y-2165D01*
Y-2133D01*
Y-2101D01*
Y-2069D01*
X468170D01*
Y-2036D01*
Y-2004D01*
Y-1972D01*
Y-1940D01*
Y-1907D01*
Y-1875D01*
Y-1843D01*
Y-1811D01*
Y-1778D01*
Y-1746D01*
X468138D01*
Y-1714D01*
Y-1681D01*
Y-1649D01*
Y-1617D01*
Y-1585D01*
Y-1552D01*
Y-1520D01*
Y-1488D01*
Y-1456D01*
Y-1423D01*
Y-1391D01*
Y-1359D01*
Y-1327D01*
Y-1294D01*
Y-1262D01*
Y-1230D01*
X468105D01*
Y-1198D01*
Y-1165D01*
Y-1133D01*
Y-1101D01*
Y-1068D01*
Y-1036D01*
D02*
G37*
%LPD*%
G36*
X494754Y-2746D02*
X494818D01*
Y-2778D01*
Y-2811D01*
Y-2843D01*
Y-2875D01*
Y-2907D01*
Y-2940D01*
Y-2972D01*
Y-3004D01*
Y-3036D01*
Y-3069D01*
Y-3101D01*
Y-3133D01*
Y-3165D01*
Y-3198D01*
Y-3230D01*
Y-3262D01*
Y-3295D01*
Y-3327D01*
Y-3359D01*
Y-3391D01*
Y-3424D01*
Y-3456D01*
Y-3488D01*
Y-3520D01*
Y-3553D01*
Y-3585D01*
Y-3617D01*
Y-3650D01*
Y-3682D01*
Y-3714D01*
Y-3746D01*
Y-3779D01*
Y-3811D01*
Y-3843D01*
Y-3875D01*
Y-3907D01*
Y-3940D01*
Y-3972D01*
Y-4004D01*
Y-4037D01*
Y-4069D01*
Y-4101D01*
Y-4133D01*
Y-4166D01*
Y-4198D01*
Y-4230D01*
Y-4262D01*
Y-4295D01*
Y-4327D01*
Y-4359D01*
Y-4391D01*
Y-4424D01*
Y-4456D01*
Y-4488D01*
Y-4521D01*
Y-4553D01*
Y-4585D01*
Y-4617D01*
Y-4650D01*
Y-4682D01*
Y-4714D01*
Y-4746D01*
Y-4779D01*
Y-4811D01*
Y-4843D01*
Y-4875D01*
Y-4908D01*
Y-4940D01*
Y-4972D01*
Y-5004D01*
Y-5037D01*
Y-5069D01*
Y-5101D01*
Y-5133D01*
Y-5166D01*
Y-5198D01*
Y-5230D01*
Y-5263D01*
Y-5295D01*
Y-5327D01*
Y-5359D01*
Y-5392D01*
Y-5424D01*
Y-5456D01*
Y-5488D01*
Y-5521D01*
Y-5553D01*
Y-5585D01*
Y-5617D01*
Y-5650D01*
Y-5682D01*
Y-5714D01*
Y-5746D01*
Y-5779D01*
Y-5811D01*
Y-5843D01*
Y-5875D01*
Y-5908D01*
Y-5940D01*
Y-5972D01*
Y-6005D01*
Y-6037D01*
Y-6069D01*
Y-6101D01*
Y-6134D01*
Y-6166D01*
Y-6198D01*
Y-6230D01*
Y-6263D01*
Y-6295D01*
Y-6327D01*
X492463D01*
Y-6295D01*
Y-6263D01*
Y-6230D01*
Y-6198D01*
Y-6166D01*
Y-6134D01*
Y-6101D01*
Y-6069D01*
Y-6037D01*
Y-6005D01*
Y-5972D01*
Y-5940D01*
Y-5908D01*
Y-5875D01*
Y-5843D01*
Y-5811D01*
Y-5779D01*
Y-5746D01*
Y-5714D01*
Y-5682D01*
Y-5650D01*
Y-5617D01*
Y-5585D01*
Y-5553D01*
Y-5521D01*
Y-5488D01*
Y-5456D01*
Y-5424D01*
Y-5392D01*
Y-5359D01*
Y-5327D01*
Y-5295D01*
Y-5263D01*
Y-5230D01*
Y-5198D01*
Y-5166D01*
Y-5133D01*
Y-5101D01*
Y-5069D01*
Y-5037D01*
Y-5004D01*
Y-4972D01*
Y-4940D01*
Y-4908D01*
Y-4875D01*
Y-4843D01*
Y-4811D01*
Y-4779D01*
Y-4746D01*
Y-4714D01*
Y-4682D01*
Y-4650D01*
Y-4617D01*
Y-4585D01*
Y-4553D01*
Y-4521D01*
Y-4488D01*
Y-4456D01*
Y-4424D01*
Y-4391D01*
Y-4359D01*
Y-4327D01*
Y-4295D01*
Y-4262D01*
Y-4230D01*
Y-4198D01*
Y-4166D01*
Y-4133D01*
Y-4101D01*
Y-4069D01*
Y-4037D01*
Y-4004D01*
Y-3972D01*
Y-3940D01*
Y-3907D01*
Y-3875D01*
Y-3843D01*
Y-3811D01*
Y-3779D01*
Y-3746D01*
Y-3714D01*
Y-3682D01*
Y-3650D01*
Y-3617D01*
Y-3585D01*
Y-3553D01*
Y-3520D01*
Y-3488D01*
Y-3456D01*
Y-3424D01*
Y-3391D01*
Y-3359D01*
Y-3327D01*
Y-3295D01*
Y-3262D01*
Y-3230D01*
Y-3198D01*
Y-3165D01*
Y-3133D01*
Y-3101D01*
Y-3069D01*
Y-3036D01*
Y-3004D01*
Y-2972D01*
Y-2940D01*
Y-2907D01*
Y-2875D01*
Y-2843D01*
Y-2811D01*
Y-2778D01*
Y-2746D01*
X492495D01*
Y-2714D01*
X492527D01*
Y-2746D01*
X494625D01*
Y-2714D01*
X494657D01*
Y-2746D01*
X494721D01*
Y-2714D01*
X494754D01*
Y-2746D01*
D02*
G37*
G36*
X487946Y-2682D02*
Y-2714D01*
Y-2746D01*
Y-2778D01*
Y-2811D01*
Y-2843D01*
Y-2875D01*
Y-2907D01*
Y-2940D01*
Y-2972D01*
Y-3004D01*
Y-3036D01*
Y-3069D01*
Y-3101D01*
Y-3133D01*
Y-3165D01*
Y-3198D01*
Y-3230D01*
Y-3262D01*
Y-3295D01*
Y-3327D01*
Y-3359D01*
Y-3391D01*
Y-3424D01*
Y-3456D01*
Y-3488D01*
Y-3520D01*
Y-3553D01*
Y-3585D01*
Y-3617D01*
Y-3650D01*
Y-3682D01*
Y-3714D01*
Y-3746D01*
Y-3779D01*
Y-3811D01*
Y-3843D01*
Y-3875D01*
Y-3907D01*
Y-3940D01*
Y-3972D01*
Y-4004D01*
Y-4037D01*
Y-4069D01*
Y-4101D01*
Y-4133D01*
Y-4166D01*
Y-4198D01*
Y-4230D01*
Y-4262D01*
Y-4295D01*
Y-4327D01*
Y-4359D01*
X485527D01*
Y-4327D01*
Y-4295D01*
Y-4262D01*
Y-4230D01*
Y-4198D01*
Y-4166D01*
Y-4133D01*
Y-4101D01*
Y-4069D01*
Y-4037D01*
Y-4004D01*
Y-3972D01*
Y-3940D01*
Y-3907D01*
Y-3875D01*
Y-3843D01*
Y-3811D01*
Y-3779D01*
Y-3746D01*
Y-3714D01*
Y-3682D01*
Y-3650D01*
Y-3617D01*
Y-3585D01*
Y-3553D01*
Y-3520D01*
Y-3488D01*
Y-3456D01*
Y-3424D01*
Y-3391D01*
Y-3359D01*
Y-3327D01*
Y-3295D01*
Y-3262D01*
Y-3230D01*
Y-3198D01*
Y-3165D01*
Y-3133D01*
Y-3101D01*
Y-3069D01*
Y-3036D01*
Y-3004D01*
Y-2972D01*
Y-2940D01*
Y-2907D01*
Y-2875D01*
Y-2843D01*
Y-2811D01*
Y-2778D01*
Y-2746D01*
Y-2714D01*
Y-2682D01*
Y-2649D01*
X487946D01*
Y-2682D01*
D02*
G37*
D31*
X384372Y-232010D02*
D03*
Y-236494D02*
D03*
X388856D02*
D03*
Y-232010D02*
D03*
D32*
X267547Y-356432D02*
Y-360430D01*
X268880Y-361763D01*
X270213Y-360430D01*
X271545Y-361763D01*
X272878Y-360430D01*
Y-356432D01*
X275544D02*
Y-360430D01*
X276877Y-361763D01*
X278210Y-360430D01*
X279543Y-361763D01*
X280876Y-360430D01*
Y-356432D01*
X283542D02*
Y-360430D01*
X284875Y-361763D01*
X286207Y-360430D01*
X287540Y-361763D01*
X288873Y-360430D01*
Y-356432D01*
X291539Y-361763D02*
Y-360430D01*
X292872D01*
Y-361763D01*
X291539D01*
X299536Y-355099D02*
Y-356432D01*
X298203D01*
X300869D01*
X299536D01*
Y-360430D01*
X300869Y-361763D01*
X304868D02*
X307534D01*
X306201D01*
Y-356432D01*
X304868D01*
X311532Y-361763D02*
Y-356432D01*
X312865D01*
X314198Y-357765D01*
Y-361763D01*
Y-357765D01*
X315531Y-356432D01*
X316864Y-357765D01*
Y-361763D01*
X319530D02*
X322196D01*
X320863D01*
Y-356432D01*
X319530D01*
X326194Y-361763D02*
Y-356432D01*
X330193D01*
X331526Y-357765D01*
Y-361763D01*
X336858Y-364429D02*
X338191D01*
X339523Y-363096D01*
Y-356432D01*
X335525D01*
X334192Y-357765D01*
Y-360430D01*
X335525Y-361763D01*
X339523D01*
X347521Y-356432D02*
X343522D01*
X342189Y-357765D01*
Y-360430D01*
X343522Y-361763D01*
X347521D01*
X351519Y-356432D02*
X354185D01*
X355518Y-357765D01*
Y-361763D01*
X351519D01*
X350187Y-360430D01*
X351519Y-359098D01*
X355518D01*
X358184Y-356432D02*
Y-361763D01*
Y-359098D01*
X359517Y-357765D01*
X360850Y-356432D01*
X362183D01*
X371513Y-353766D02*
Y-361763D01*
X367514D01*
X366181Y-360430D01*
Y-357765D01*
X367514Y-356432D01*
X371513D01*
X374179Y-361763D02*
Y-360430D01*
X375512D01*
Y-361763D01*
X374179D01*
X386175Y-356432D02*
X382176D01*
X380843Y-357765D01*
Y-360430D01*
X382176Y-361763D01*
X386175D01*
X390174D02*
X392840D01*
X394172Y-360430D01*
Y-357765D01*
X392840Y-356432D01*
X390174D01*
X388841Y-357765D01*
Y-360430D01*
X390174Y-361763D01*
X396838D02*
Y-356432D01*
X398171D01*
X399504Y-357765D01*
Y-361763D01*
Y-357765D01*
X400837Y-356432D01*
X402170Y-357765D01*
Y-361763D01*
D33*
X482677Y-262598D02*
D03*
Y-264173D02*
D03*
Y-265748D02*
D03*
Y-267323D02*
D03*
Y-268898D02*
D03*
X477953D02*
D03*
Y-267323D02*
D03*
Y-265748D02*
D03*
Y-264173D02*
D03*
X327953Y-236614D02*
D03*
Y-238189D02*
D03*
Y-239764D02*
D03*
Y-241339D02*
D03*
Y-242913D02*
D03*
X323228D02*
D03*
Y-241339D02*
D03*
Y-239764D02*
D03*
Y-238189D02*
D03*
X341732Y-289764D02*
D03*
Y-291339D02*
D03*
Y-292913D02*
D03*
Y-294488D02*
D03*
Y-296063D02*
D03*
X337008D02*
D03*
Y-294488D02*
D03*
Y-292913D02*
D03*
Y-291339D02*
D03*
X322835Y-290551D02*
D03*
Y-292126D02*
D03*
Y-293701D02*
D03*
Y-295276D02*
D03*
Y-296850D02*
D03*
X318110D02*
D03*
Y-295276D02*
D03*
Y-293701D02*
D03*
Y-292126D02*
D03*
D34*
X480315Y-262795D02*
D03*
Y-268701D02*
D03*
X325590Y-236811D02*
D03*
Y-242717D02*
D03*
X339370Y-289961D02*
D03*
Y-295866D02*
D03*
X320472Y-290748D02*
D03*
Y-296654D02*
D03*
D35*
X186614Y-92126D02*
D03*
X188189Y-92126D02*
D03*
X189764D02*
D03*
X191338D02*
D03*
X192914Y-92126D02*
D03*
X192913Y-96851D02*
D03*
X191339Y-96850D02*
D03*
X189764D02*
D03*
X188189D02*
D03*
X280315Y-197638D02*
D03*
X281890D02*
D03*
X283465D02*
D03*
X285039Y-197638D02*
D03*
X285039Y-192913D02*
D03*
X283464Y-192913D02*
D03*
X281890D02*
D03*
X280315D02*
D03*
X278740Y-192913D02*
D03*
D36*
X186811Y-94488D02*
D03*
X192716Y-94488D02*
D03*
X284842Y-195275D02*
D03*
X278937Y-195276D02*
D03*
D37*
X615256Y-241005D02*
D03*
D38*
X84981Y-123809D02*
D03*
D39*
X79076Y-114655D02*
D03*
X81044D02*
D03*
X83013D02*
D03*
X84981D02*
D03*
X86950D02*
D03*
X88918D02*
D03*
X90887D02*
D03*
X90887Y-132963D02*
D03*
X88918D02*
D03*
X86950D02*
D03*
X84981D02*
D03*
X83013D02*
D03*
X81044D02*
D03*
X79076D02*
D03*
D40*
X94135Y-117904D02*
D03*
Y-119872D02*
D03*
Y-121841D02*
D03*
Y-123809D02*
D03*
Y-125778D02*
D03*
Y-127746D02*
D03*
Y-129715D02*
D03*
X75828Y-125778D02*
D03*
Y-123809D02*
D03*
Y-121841D02*
D03*
Y-119872D02*
D03*
Y-117904D02*
D03*
Y-127746D02*
D03*
Y-129715D02*
D03*
D41*
X58407Y-133652D02*
D03*
X64312D02*
D03*
D42*
X47777Y-115541D02*
D03*
X50926D02*
D03*
X50926Y-111604D02*
D03*
X47777D02*
D03*
X50926Y-108061D02*
D03*
X47777D02*
D03*
X160236Y-54331D02*
D03*
X163386D02*
D03*
X544882Y-300787D02*
D03*
X541732D02*
D03*
X160236Y-59055D02*
D03*
X163386D02*
D03*
X548819Y-300787D02*
D03*
X551968D02*
D03*
X181335Y-132874D02*
D03*
X184485D02*
D03*
X181335Y-113583D02*
D03*
X184485D02*
D03*
D43*
X63918Y-121053D02*
D03*
Y-126565D02*
D03*
X253082Y-115065D02*
D03*
Y-120577D02*
D03*
X611811Y-38189D02*
D03*
Y-43701D02*
D03*
D44*
X57422Y-120856D02*
D03*
Y-125581D02*
D03*
D45*
X58210Y-108061D02*
D03*
X64903D02*
D03*
D46*
X128523Y-116147D02*
D03*
X134034D02*
D03*
X128459Y-110462D02*
D03*
X133971D02*
D03*
D47*
X262456Y-120276D02*
D03*
Y-113189D02*
D03*
X620866Y-35827D02*
D03*
Y-42913D02*
D03*
D48*
X264469Y-128937D02*
D03*
X276083D02*
D03*
Y-141142D02*
D03*
X264469D02*
D03*
X276083Y-152559D02*
D03*
X264469D02*
D03*
D49*
X436811Y-137992D02*
D03*
Y-144095D02*
D03*
Y-159646D02*
D03*
Y-153543D02*
D03*
X408858Y-137992D02*
D03*
Y-144095D02*
D03*
Y-153543D02*
D03*
Y-159646D02*
D03*
X47441Y-27362D02*
D03*
Y-21260D02*
D03*
Y-5709D02*
D03*
Y-11811D02*
D03*
X75394Y-27362D02*
D03*
Y-21260D02*
D03*
Y-11811D02*
D03*
Y-5709D02*
D03*
D50*
X427559Y-137992D02*
D03*
X422835D02*
D03*
X418110D02*
D03*
Y-159646D02*
D03*
X422835D02*
D03*
X427559D02*
D03*
Y-148819D02*
D03*
X422835D02*
D03*
X418110D02*
D03*
X427559Y-153543D02*
D03*
X422835D02*
D03*
X418110D02*
D03*
X422835Y-144095D02*
D03*
X418110D02*
D03*
X61417Y-21260D02*
D03*
Y-16535D02*
D03*
X56693Y-27362D02*
D03*
X61417D02*
D03*
X66142D02*
D03*
Y-5709D02*
D03*
X61417D02*
D03*
X56693D02*
D03*
Y-16535D02*
D03*
X66142D02*
D03*
X56693Y-11811D02*
D03*
X61417D02*
D03*
X66142D02*
D03*
Y-21260D02*
D03*
D51*
X427409Y-144269D02*
D03*
X56843Y-21085D02*
D03*
D52*
X159390Y-99990D02*
D03*
Y-101565D02*
D03*
Y-103139D02*
D03*
X163445D02*
D03*
Y-101565D02*
D03*
Y-99990D02*
D03*
D53*
X161417Y-101565D02*
D03*
D54*
X109095Y12205D02*
D03*
X85394D02*
D03*
X72480Y12598D02*
D03*
X48779D02*
D03*
X334567Y-133858D02*
D03*
X358268D02*
D03*
X83819Y-77165D02*
D03*
X107520D02*
D03*
D55*
X382776Y-241437D02*
D03*
X385335D02*
D03*
X387894D02*
D03*
X390453D02*
D03*
Y-227067D02*
D03*
X387894D02*
D03*
X385335D02*
D03*
X382776D02*
D03*
D56*
X393799Y-238090D02*
D03*
Y-235531D02*
D03*
Y-232972D02*
D03*
Y-230413D02*
D03*
X379429D02*
D03*
Y-232972D02*
D03*
Y-235531D02*
D03*
Y-238090D02*
D03*
D57*
X609547Y-277461D02*
D03*
Y-280020D02*
D03*
Y-274902D02*
D03*
Y-282579D02*
D03*
Y-285138D02*
D03*
D58*
X620079Y-284547D02*
D03*
Y-275492D02*
D03*
D59*
X147047Y-26033D02*
D03*
Y-33907D02*
D03*
Y-41781D02*
D03*
Y-49655D02*
D03*
X129547Y-26033D02*
D03*
Y-33907D02*
D03*
Y-41781D02*
D03*
Y-18159D02*
D03*
Y-73277D02*
D03*
Y-57529D02*
D03*
Y-65403D02*
D03*
Y-49655D02*
D03*
X147047Y-73277D02*
D03*
Y-65403D02*
D03*
Y-57529D02*
D03*
Y-18159D02*
D03*
Y-49655D02*
D03*
Y-57529D02*
D03*
Y-65403D02*
D03*
Y-73277D02*
D03*
X129547Y-49655D02*
D03*
Y-65403D02*
D03*
Y-57529D02*
D03*
Y-73277D02*
D03*
D60*
X133957Y-9843D02*
D03*
X136909D02*
D03*
X489862Y-314173D02*
D03*
X492815D02*
D03*
X177657Y-87795D02*
D03*
X180610D02*
D03*
X178051Y-101181D02*
D03*
X181004D02*
D03*
X201476Y-87795D02*
D03*
X198524D02*
D03*
X200295Y-102756D02*
D03*
X197343D02*
D03*
X180610Y-92126D02*
D03*
X177657D02*
D03*
X198524Y-91732D02*
D03*
X201476D02*
D03*
X609547Y-252756D02*
D03*
X612500D02*
D03*
X294783Y-194095D02*
D03*
X291831D02*
D03*
X292815Y-189764D02*
D03*
X289862D02*
D03*
X269783Y-192126D02*
D03*
X272736D02*
D03*
X269783Y-196457D02*
D03*
X272736D02*
D03*
D61*
X597835Y-233071D02*
D03*
X603740D02*
D03*
X605905Y-186107D02*
D03*
X600000D02*
D03*
X600591Y-150000D02*
D03*
X594685D02*
D03*
X457480Y-76378D02*
D03*
X451575D02*
D03*
X92323Y-92126D02*
D03*
X98228D02*
D03*
X597835Y-220472D02*
D03*
X603740D02*
D03*
X597835Y-226772D02*
D03*
X603740D02*
D03*
X31693Y-1969D02*
D03*
X25787D02*
D03*
X31693Y4921D02*
D03*
X25787D02*
D03*
X31693Y11811D02*
D03*
X25787D02*
D03*
X31693Y18701D02*
D03*
X25787D02*
D03*
D62*
X595036Y-211353D02*
D03*
Y-206353D02*
D03*
Y-201353D02*
D03*
Y-196353D02*
D03*
X624918D02*
D03*
Y-201353D02*
D03*
Y-206353D02*
D03*
Y-211353D02*
D03*
D63*
X590530Y-163898D02*
D03*
Y-173898D02*
D03*
X624430Y-163898D02*
D03*
Y-173898D02*
D03*
D64*
X599016Y-144488D02*
D03*
X595472D02*
D03*
X492323Y-303543D02*
D03*
X495866D02*
D03*
X484842Y-317717D02*
D03*
X488386D02*
D03*
X489567Y-310236D02*
D03*
X493110D02*
D03*
X473819Y-315354D02*
D03*
X470276D02*
D03*
X144685Y-11811D02*
D03*
X141142D02*
D03*
X137598Y-6299D02*
D03*
X134055D02*
D03*
X312402Y-243307D02*
D03*
X315945D02*
D03*
X370669Y-236614D02*
D03*
X374213D02*
D03*
X370669Y-241339D02*
D03*
X374213D02*
D03*
X396654Y-219291D02*
D03*
X393110D02*
D03*
X337992Y-235827D02*
D03*
X334449D02*
D03*
X320669Y-250787D02*
D03*
X324213D02*
D03*
X320669Y-228740D02*
D03*
X324213D02*
D03*
X338386Y-242913D02*
D03*
X334842D02*
D03*
X315158Y-236221D02*
D03*
X318701D02*
D03*
X337598Y-281102D02*
D03*
X341142D02*
D03*
X337992Y-303150D02*
D03*
X341535D02*
D03*
X318307Y-283465D02*
D03*
X321850D02*
D03*
X317913Y-303543D02*
D03*
X321457D02*
D03*
X600689Y-238976D02*
D03*
X604232D02*
D03*
X352362Y-288583D02*
D03*
X348819D02*
D03*
X351575Y-296063D02*
D03*
X348031D02*
D03*
X308071Y-289370D02*
D03*
X311614D02*
D03*
X307283Y-296457D02*
D03*
X310827D02*
D03*
X600689Y-242913D02*
D03*
X604232D02*
D03*
X613976Y-228740D02*
D03*
X610433D02*
D03*
X620669Y-228346D02*
D03*
X624213D02*
D03*
D65*
X478346Y-303937D02*
D03*
X150787Y394D02*
D03*
D66*
X475394Y-298237D02*
D03*
X477362D02*
D03*
X479331D02*
D03*
X481299D02*
D03*
Y-309637D02*
D03*
X479331D02*
D03*
X477362D02*
D03*
X475394D02*
D03*
X147835Y6094D02*
D03*
X149803D02*
D03*
X151772D02*
D03*
X153740D02*
D03*
Y-5306D02*
D03*
X151772D02*
D03*
X149803D02*
D03*
X147835D02*
D03*
D67*
X484047Y-300984D02*
D03*
Y-302953D02*
D03*
Y-304921D02*
D03*
Y-306890D02*
D03*
X472647D02*
D03*
Y-304921D02*
D03*
Y-302953D02*
D03*
Y-300984D02*
D03*
X156487Y3347D02*
D03*
Y1378D02*
D03*
Y-591D02*
D03*
Y-2559D02*
D03*
X145087D02*
D03*
Y-591D02*
D03*
Y1378D02*
D03*
Y3347D02*
D03*
D68*
X482677Y-276476D02*
D03*
Y-279429D02*
D03*
X483071Y-256988D02*
D03*
Y-254035D02*
D03*
X479921Y-279429D02*
D03*
Y-276476D02*
D03*
X485827Y-279429D02*
D03*
Y-276476D02*
D03*
X476772Y-254035D02*
D03*
Y-256988D02*
D03*
X487402Y-254035D02*
D03*
Y-256988D02*
D03*
X465748Y-308760D02*
D03*
Y-311713D02*
D03*
X488583Y-295177D02*
D03*
Y-292224D02*
D03*
X472835Y-292028D02*
D03*
Y-289075D02*
D03*
X146850Y14272D02*
D03*
Y17224D02*
D03*
X164567Y9941D02*
D03*
Y12894D02*
D03*
X158661Y-9941D02*
D03*
Y-12894D02*
D03*
X283858Y-204232D02*
D03*
Y-207185D02*
D03*
X285827Y-186909D02*
D03*
Y-183957D02*
D03*
X279528Y-204429D02*
D03*
Y-207382D02*
D03*
X278346Y-186909D02*
D03*
Y-183957D02*
D03*
D69*
X461417Y-308465D02*
D03*
Y-312008D02*
D03*
X476772Y-291929D02*
D03*
Y-288386D02*
D03*
X483465Y-291535D02*
D03*
Y-287992D02*
D03*
X466142Y-298228D02*
D03*
Y-294685D02*
D03*
X142520Y13189D02*
D03*
Y16732D02*
D03*
X162598Y-9646D02*
D03*
Y-13189D02*
D03*
X159843Y9646D02*
D03*
Y13189D02*
D03*
X151181Y14370D02*
D03*
Y17913D02*
D03*
X153543Y-10433D02*
D03*
Y-13976D02*
D03*
X169291Y9646D02*
D03*
Y13189D02*
D03*
X382677Y-249803D02*
D03*
Y-246260D02*
D03*
X333071Y-282480D02*
D03*
Y-286024D02*
D03*
Y-302559D02*
D03*
Y-299016D02*
D03*
X327953Y-282480D02*
D03*
Y-286024D02*
D03*
X328740Y-302362D02*
D03*
Y-298819D02*
D03*
D70*
X203839Y-56693D02*
D03*
X174114Y-2559D02*
D03*
X203839Y-3543D02*
D03*
X174114Y-4528D02*
D03*
X203839Y-5512D02*
D03*
X174114Y-6496D02*
D03*
X203839Y-7480D02*
D03*
X174114Y-8465D02*
D03*
X203839Y-9449D02*
D03*
X174114Y-10433D02*
D03*
X203839Y-11417D02*
D03*
X174114Y-12402D02*
D03*
X203839Y-13386D02*
D03*
X174114Y-14370D02*
D03*
X203839Y-15354D02*
D03*
X174114Y-16339D02*
D03*
X203839Y-17323D02*
D03*
X174114Y-18307D02*
D03*
X203839Y-19291D02*
D03*
X174114Y-20276D02*
D03*
X203839Y-21260D02*
D03*
X174114Y-22244D02*
D03*
X203839Y-23228D02*
D03*
X174114Y-24213D02*
D03*
X203839Y-25197D02*
D03*
X174114Y-26181D02*
D03*
X203839Y-27165D02*
D03*
X174114Y-28150D02*
D03*
X203839Y-29134D02*
D03*
X174114Y-30118D02*
D03*
X203839Y-31102D02*
D03*
X174114Y-32087D02*
D03*
X203839Y-33071D02*
D03*
X174114Y-34055D02*
D03*
X203839Y-35039D02*
D03*
X174114Y-36024D02*
D03*
X203839Y-37008D02*
D03*
X174114Y-37992D02*
D03*
X203839Y-38976D02*
D03*
X174114Y-39961D02*
D03*
X203839Y-40945D02*
D03*
X174114Y-41929D02*
D03*
X203839Y-42913D02*
D03*
X174114Y-43898D02*
D03*
X203839Y-44882D02*
D03*
X174114Y-45866D02*
D03*
X203839Y-46850D02*
D03*
X174114Y-47835D02*
D03*
X203839Y-48819D02*
D03*
X174114Y-49803D02*
D03*
X203839Y-50787D02*
D03*
X174114Y-51772D02*
D03*
X203839Y-52756D02*
D03*
X174114Y-53740D02*
D03*
X203839Y-54724D02*
D03*
X174114Y-55709D02*
D03*
X203839Y-66535D02*
D03*
Y-68504D02*
D03*
Y-70472D02*
D03*
Y-72441D02*
D03*
Y-74410D02*
D03*
X174114Y-65551D02*
D03*
Y-67520D02*
D03*
Y-69488D02*
D03*
Y-71457D02*
D03*
Y-73425D02*
D03*
Y-75394D02*
D03*
D71*
X177165Y1772D02*
D03*
Y-79724D02*
D03*
D72*
X553543Y-262402D02*
D03*
X499409Y-292126D02*
D03*
X500394Y-262402D02*
D03*
X501378Y-292126D02*
D03*
X502362Y-262402D02*
D03*
X503346Y-292126D02*
D03*
X504331Y-262402D02*
D03*
X505315Y-292126D02*
D03*
X506299Y-262402D02*
D03*
X507283Y-292126D02*
D03*
X508268Y-262402D02*
D03*
X509252Y-292126D02*
D03*
X510236Y-262402D02*
D03*
X511221Y-292126D02*
D03*
X512205Y-262402D02*
D03*
X513189Y-292126D02*
D03*
X514173Y-262402D02*
D03*
X515158Y-292126D02*
D03*
X516142Y-262402D02*
D03*
X517126Y-292126D02*
D03*
X518110Y-262402D02*
D03*
X519095Y-292126D02*
D03*
X520079Y-262402D02*
D03*
X521063Y-292126D02*
D03*
X522047Y-262402D02*
D03*
X523032Y-292126D02*
D03*
X524016Y-262402D02*
D03*
X525000Y-292126D02*
D03*
X525984Y-262402D02*
D03*
X526968Y-292126D02*
D03*
X527953Y-262402D02*
D03*
X528937Y-292126D02*
D03*
X529921Y-262402D02*
D03*
X530905Y-292126D02*
D03*
X531890Y-262402D02*
D03*
X532874Y-292126D02*
D03*
X533858Y-262402D02*
D03*
X534842Y-292126D02*
D03*
X535827Y-262402D02*
D03*
X536811Y-292126D02*
D03*
X537795Y-262402D02*
D03*
X538779Y-292126D02*
D03*
X539764Y-262402D02*
D03*
X540748Y-292126D02*
D03*
X541732Y-262402D02*
D03*
X542717Y-292126D02*
D03*
X543701Y-262402D02*
D03*
X544685Y-292126D02*
D03*
X545669Y-262402D02*
D03*
X546654Y-292126D02*
D03*
X547638Y-262402D02*
D03*
X548622Y-292126D02*
D03*
X549606Y-262402D02*
D03*
X550591Y-292126D02*
D03*
X551575Y-262402D02*
D03*
X552559Y-292126D02*
D03*
X563386Y-262402D02*
D03*
X565354D02*
D03*
X567323D02*
D03*
X569291D02*
D03*
X571260D02*
D03*
X562402Y-292126D02*
D03*
X564370D02*
D03*
X566339D02*
D03*
X568307D02*
D03*
X570276D02*
D03*
X572244D02*
D03*
D73*
X495079Y-289075D02*
D03*
X576575D02*
D03*
D74*
X545448Y-27614D02*
D03*
Y-45614D02*
D03*
D75*
X572698Y-36614D02*
D03*
D76*
X166178Y-135679D02*
D03*
X164209Y-117471D02*
D03*
Y-135679D02*
D03*
X162241D02*
D03*
X160272D02*
D03*
Y-117471D02*
D03*
X162241D02*
D03*
X166178D02*
D03*
D77*
X169377Y-135433D02*
D03*
Y-119685D02*
D03*
Y-117717D02*
D03*
Y-121653D02*
D03*
Y-123622D02*
D03*
Y-125591D02*
D03*
Y-127559D02*
D03*
Y-129528D02*
D03*
Y-131496D02*
D03*
Y-133465D02*
D03*
X157073Y-135433D02*
D03*
Y-133465D02*
D03*
Y-131496D02*
D03*
Y-129528D02*
D03*
Y-127559D02*
D03*
Y-125591D02*
D03*
Y-123622D02*
D03*
Y-121653D02*
D03*
Y-119685D02*
D03*
Y-117717D02*
D03*
D78*
X105282Y-19291D02*
D03*
D79*
X97408D02*
D03*
D80*
Y-10197D02*
D03*
D81*
X103943D02*
D03*
D82*
X107132D02*
D03*
D83*
X110958Y-7480D02*
D03*
Y-10630D02*
D03*
Y-13780D02*
D03*
Y-16929D02*
D03*
Y-20079D02*
D03*
X90158D02*
D03*
Y-16929D02*
D03*
Y-13780D02*
D03*
Y-10630D02*
D03*
Y-7480D02*
D03*
X411647Y-122343D02*
D03*
Y-119193D02*
D03*
Y-116043D02*
D03*
Y-112894D02*
D03*
Y-109744D02*
D03*
X432447D02*
D03*
Y-112894D02*
D03*
Y-116043D02*
D03*
Y-119193D02*
D03*
Y-122343D02*
D03*
D84*
X106857Y-24180D02*
D03*
X103707D02*
D03*
X100557D02*
D03*
X97408D02*
D03*
X94258D02*
D03*
Y-3379D02*
D03*
X97408D02*
D03*
X100557D02*
D03*
X103707D02*
D03*
X106857D02*
D03*
X428346Y-126443D02*
D03*
X425197D02*
D03*
X422047D02*
D03*
X418898D02*
D03*
X415748D02*
D03*
Y-105643D02*
D03*
X418898D02*
D03*
X422047D02*
D03*
X425197D02*
D03*
X428346D02*
D03*
D85*
X453937Y-136181D02*
D03*
Y-159882D02*
D03*
X457480Y-90118D02*
D03*
Y-113819D02*
D03*
D86*
X356750Y-119882D02*
D03*
X352982D02*
D03*
D87*
X390654Y-113429D02*
D03*
Y-110551D02*
D03*
X14173Y-299864D02*
D03*
Y-296986D02*
D03*
D88*
X353029Y-113189D02*
D03*
X356703D02*
D03*
D89*
X383268Y-114567D02*
D03*
Y-109055D02*
D03*
X148425Y-104336D02*
D03*
Y-98824D02*
D03*
D90*
X428300Y-192653D02*
D03*
X424560Y-201048D02*
D03*
X432040D02*
D03*
X424560Y-192653D02*
D03*
D91*
X432040D02*
D03*
D92*
X373083Y-155512D02*
D03*
X378083D02*
D03*
X388083Y-134252D02*
D03*
X383083D02*
D03*
X378083D02*
D03*
X373083D02*
D03*
X383083Y-155512D02*
D03*
X388083D02*
D03*
X613406Y-83465D02*
D03*
X608405D02*
D03*
X598406Y-62205D02*
D03*
X603406D02*
D03*
X608405D02*
D03*
X613406D02*
D03*
X603406Y-83465D02*
D03*
X598406D02*
D03*
D93*
X399410Y-120866D02*
D03*
X388976D02*
D03*
X77067Y-40157D02*
D03*
X87500D02*
D03*
X589764Y-52362D02*
D03*
X600197D02*
D03*
D94*
X66102Y-43355D02*
D03*
X44842Y-58355D02*
D03*
Y-53355D02*
D03*
X66102Y-48355D02*
D03*
Y-53355D02*
D03*
Y-58355D02*
D03*
X44842Y-48355D02*
D03*
Y-43355D02*
D03*
D95*
X25686Y-18898D02*
D03*
X35731D02*
D03*
X464961Y-125197D02*
D03*
X454915D02*
D03*
X25686Y-9843D02*
D03*
X35731D02*
D03*
D96*
X416535Y-120768D02*
D03*
D97*
Y-112894D02*
D03*
D98*
X425630D02*
D03*
D99*
Y-119429D02*
D03*
D100*
Y-122618D02*
D03*
D101*
X443307Y-112300D02*
D03*
Y-122346D02*
D03*
D102*
X362402Y-111811D02*
D03*
X375394D02*
D03*
X74616Y-61723D02*
D03*
X87608D02*
D03*
D103*
X334646Y-153937D02*
D03*
X358268D02*
D03*
D104*
X103543Y-61811D02*
D03*
Y-38189D02*
D03*
D105*
X93299Y-99606D02*
D03*
X97253D02*
D03*
X471662Y-76378D02*
D03*
X467708D02*
D03*
D106*
X386319Y-217717D02*
D03*
X382972D02*
D03*
X131004Y-348031D02*
D03*
X134350D02*
D03*
X131004Y-352362D02*
D03*
X134350D02*
D03*
X18799Y-350000D02*
D03*
X22146D02*
D03*
X3445Y-234646D02*
D03*
X6791D02*
D03*
X23524Y-239370D02*
D03*
X26870D02*
D03*
X23130Y-192520D02*
D03*
X26476D02*
D03*
X405807Y-233071D02*
D03*
X409154D02*
D03*
X405413Y-238189D02*
D03*
X408760D02*
D03*
X404626Y-219685D02*
D03*
X407972D02*
D03*
X404626Y-224016D02*
D03*
X407972D02*
D03*
X374902Y-217717D02*
D03*
X371555D02*
D03*
D107*
X387509Y-173797D02*
D03*
X334360Y-189741D02*
D03*
X387509D02*
D03*
X389478D02*
D03*
Y-173797D02*
D03*
X379635D02*
D03*
X369793D02*
D03*
X359950D02*
D03*
X350108D02*
D03*
X340265D02*
D03*
X330423D02*
D03*
X320580D02*
D03*
X379635Y-189741D02*
D03*
X369793D02*
D03*
X359950D02*
D03*
X350108D02*
D03*
X340265D02*
D03*
X330423D02*
D03*
X320580D02*
D03*
X385541D02*
D03*
Y-173797D02*
D03*
X332391Y-189741D02*
D03*
X352076Y-173797D02*
D03*
X328454Y-189741D02*
D03*
X312706Y-173797D02*
D03*
X322549Y-189741D02*
D03*
X312706D02*
D03*
X318612D02*
D03*
X357982Y-173797D02*
D03*
X344202D02*
D03*
X314675D02*
D03*
X316643Y-189741D02*
D03*
X356013Y-173797D02*
D03*
X322549D02*
D03*
X328454D02*
D03*
X318612D02*
D03*
X354045D02*
D03*
X342234D02*
D03*
X334360D02*
D03*
X324517D02*
D03*
X314675Y-189741D02*
D03*
X316643Y-173797D02*
D03*
X324517Y-189741D02*
D03*
X363887Y-173797D02*
D03*
X361919D02*
D03*
X326486D02*
D03*
X332391D02*
D03*
X338297Y-189741D02*
D03*
X336328D02*
D03*
X375698Y-173797D02*
D03*
X352076Y-189741D02*
D03*
X356013D02*
D03*
X381604Y-173797D02*
D03*
X346171Y-189741D02*
D03*
X361919D02*
D03*
X365856D02*
D03*
X373730D02*
D03*
X377667Y-173797D02*
D03*
X367824D02*
D03*
X348139Y-189741D02*
D03*
X326486D02*
D03*
X381604D02*
D03*
X383572Y-173797D02*
D03*
X371761D02*
D03*
X365856D02*
D03*
X373730D02*
D03*
X357982Y-189741D02*
D03*
X354045D02*
D03*
X375698D02*
D03*
X363887D02*
D03*
X383572D02*
D03*
X367824D02*
D03*
X342234D02*
D03*
X344202D02*
D03*
X338297Y-173797D02*
D03*
X336328D02*
D03*
X348139D02*
D03*
X346171D02*
D03*
X371761Y-189741D02*
D03*
X377667D02*
D03*
X357972Y-321918D02*
D03*
X359940D02*
D03*
X334350D02*
D03*
X318602D02*
D03*
X330413D02*
D03*
X338287D02*
D03*
X326476D02*
D03*
X348129D02*
D03*
X344192D02*
D03*
X328444Y-337862D02*
D03*
X336318D02*
D03*
X330413D02*
D03*
X318602D02*
D03*
X320570Y-321918D02*
D03*
X324507D02*
D03*
X375688D02*
D03*
X354035D02*
D03*
X334350Y-337862D02*
D03*
X324507D02*
D03*
X328444Y-321918D02*
D03*
X336318D02*
D03*
X340255D02*
D03*
X356003D02*
D03*
X320570Y-337862D02*
D03*
X346161Y-321918D02*
D03*
X350098D02*
D03*
X326476Y-337862D02*
D03*
X365846Y-321918D02*
D03*
X363877D02*
D03*
X369783Y-337862D02*
D03*
X375688D02*
D03*
X340255D02*
D03*
X338287D02*
D03*
X377657Y-321918D02*
D03*
X385531Y-337862D02*
D03*
X387499Y-321918D02*
D03*
X363877Y-337862D02*
D03*
X377657D02*
D03*
X367814D02*
D03*
X365846D02*
D03*
X359940D02*
D03*
X348129D02*
D03*
X354035D02*
D03*
X383562D02*
D03*
X373720D02*
D03*
X379625D02*
D03*
X346161D02*
D03*
X385531Y-321918D02*
D03*
X387499Y-337862D02*
D03*
X357972D02*
D03*
X344192D02*
D03*
X383562Y-321918D02*
D03*
X389468D02*
D03*
X379625D02*
D03*
X389468Y-337862D02*
D03*
X373720Y-321918D02*
D03*
X350098Y-337862D02*
D03*
X356003D02*
D03*
X369783Y-321918D02*
D03*
X316633Y-337862D02*
D03*
Y-321918D02*
D03*
X381594D02*
D03*
X371751D02*
D03*
X361909D02*
D03*
X352066D02*
D03*
X342224D02*
D03*
X332381D02*
D03*
X322539D02*
D03*
X381594Y-337862D02*
D03*
X371751D02*
D03*
X361909D02*
D03*
X352066D02*
D03*
X342224D02*
D03*
X332381D02*
D03*
X322539D02*
D03*
X312696D02*
D03*
Y-321918D02*
D03*
X314665D02*
D03*
X367814D02*
D03*
X314665Y-337862D02*
D03*
D108*
X395083Y-181814D02*
D03*
X307091D02*
D03*
X395083Y-329845D02*
D03*
X307091D02*
D03*
D109*
X238209Y-113386D02*
D03*
X233209D02*
D03*
X228209D02*
D03*
X223209D02*
D03*
X238209Y-132283D02*
D03*
X233209D02*
D03*
X228209D02*
D03*
X223209D02*
D03*
D110*
X214193Y-112795D02*
D03*
X209193D02*
D03*
X204193D02*
D03*
X199193D02*
D03*
X214193Y-131299D02*
D03*
X209193D02*
D03*
X204193D02*
D03*
X199193D02*
D03*
D111*
X182516Y-128347D02*
D03*
Y-118504D02*
D03*
D112*
X189209Y-127323D02*
D03*
Y-131339D02*
D03*
Y-117480D02*
D03*
Y-121496D02*
D03*
D113*
X168110Y-100132D02*
D03*
Y-103805D02*
D03*
D114*
X560778Y-328917D02*
D03*
X545030D02*
D03*
X552904D02*
D03*
X537156D02*
D03*
X560778Y-311417D02*
D03*
X552904D02*
D03*
X545030D02*
D03*
X537156D02*
D03*
X513534D02*
D03*
X521408D02*
D03*
X529282D02*
D03*
X537156D02*
D03*
X513534Y-328917D02*
D03*
X521408D02*
D03*
X529282D02*
D03*
X505660D02*
D03*
X560778D02*
D03*
X545030D02*
D03*
X552904D02*
D03*
X537156D02*
D03*
X560778Y-311417D02*
D03*
X552904D02*
D03*
X545030D02*
D03*
X505660D02*
D03*
D115*
X428390Y-355832D02*
D03*
X419531Y-358391D02*
D03*
Y-353273D02*
D03*
X473173Y-356620D02*
D03*
X464315Y-359179D02*
D03*
Y-354061D02*
D03*
X511594Y-356296D02*
D03*
X502736Y-358855D02*
D03*
Y-353737D02*
D03*
X556575Y-356099D02*
D03*
X547717Y-358659D02*
D03*
Y-353540D02*
D03*
D116*
X481441Y-356620D02*
D03*
X489315D02*
D03*
X436953Y-355832D02*
D03*
X444827D02*
D03*
X521339Y-356296D02*
D03*
X529213D02*
D03*
X565827Y-356690D02*
D03*
X573701D02*
D03*
D117*
X13973Y-210630D02*
D03*
Y-262795D02*
D03*
X13973Y-157332D02*
D03*
X13973Y-316929D02*
D03*
D118*
X19976Y-216437D02*
D03*
Y-204823D02*
D03*
Y-256988D02*
D03*
Y-268602D02*
D03*
X19976Y-151525D02*
D03*
Y-163139D02*
D03*
X19976Y-311122D02*
D03*
Y-322736D02*
D03*
D119*
X-1181Y-349311D02*
D03*
Y-345965D02*
D03*
X390945Y-249114D02*
D03*
Y-252461D02*
D03*
X386614Y-249114D02*
D03*
Y-252461D02*
D03*
X401575Y-249114D02*
D03*
Y-252461D02*
D03*
X396850Y-249114D02*
D03*
Y-252461D02*
D03*
D120*
X8403Y-237795D02*
D03*
X11282D02*
D03*
X5647Y-349213D02*
D03*
X8526D02*
D03*
X10372Y-193307D02*
D03*
X13250D02*
D03*
X616006Y-302756D02*
D03*
X613128D02*
D03*
D121*
X-4724Y-178543D02*
D03*
X2756D02*
D03*
Y-187205D02*
D03*
X2756Y-291732D02*
D03*
Y-283071D02*
D03*
X-4724D02*
D03*
D122*
X-3937Y-187205D02*
D03*
X-3937Y-291732D02*
D03*
D123*
X622047Y-343307D02*
D03*
Y-333307D02*
D03*
Y-323307D02*
D03*
Y-313307D02*
D03*
Y-353307D02*
D03*
X602559D02*
D03*
Y-343307D02*
D03*
Y-333307D02*
D03*
Y-323307D02*
D03*
Y-313307D02*
D03*
D124*
X153150Y-103459D02*
D03*
Y-99691D02*
D03*
D125*
X127981Y-132385D02*
D03*
X130540D02*
D03*
X127981Y-124314D02*
D03*
X130540D02*
D03*
X133099D02*
D03*
X135658D02*
D03*
Y-132385D02*
D03*
X133099D02*
D03*
D126*
X-18406Y-176772D02*
D03*
Y-187795D02*
D03*
Y-59646D02*
D03*
Y-70669D02*
D03*
Y-240551D02*
D03*
Y-229528D02*
D03*
Y-294094D02*
D03*
Y-283071D02*
D03*
Y-346850D02*
D03*
Y-335827D02*
D03*
Y-113976D02*
D03*
Y-102953D02*
D03*
D127*
X-19685Y-180512D02*
D03*
Y-184055D02*
D03*
Y-63386D02*
D03*
Y-66929D02*
D03*
Y-236811D02*
D03*
Y-233268D02*
D03*
Y-290354D02*
D03*
Y-286811D02*
D03*
Y-343110D02*
D03*
Y-339567D02*
D03*
Y-110236D02*
D03*
Y-106693D02*
D03*
D128*
X612648Y-256693D02*
D03*
X608612D02*
D03*
D129*
X610827Y-235433D02*
D03*
X612598D02*
D03*
X614370D02*
D03*
X616142D02*
D03*
X617913D02*
D03*
X619685D02*
D03*
Y-246579D02*
D03*
X617913D02*
D03*
X616142D02*
D03*
X614370D02*
D03*
X612598D02*
D03*
D130*
X610827D02*
D03*
D131*
X605418Y-300000D02*
D03*
X599307D02*
D03*
D132*
X596063Y-292126D02*
D03*
X600000D02*
D03*
X608661Y-261024D02*
D03*
X612598D02*
D03*
D133*
X550787Y-64567D02*
D03*
X576772D02*
D03*
D134*
X261126Y-299333D02*
D03*
Y-211341D02*
D03*
X448528D02*
D03*
Y-299333D02*
D03*
D135*
X269054Y-262222D02*
D03*
Y-264190D02*
D03*
Y-238600D02*
D03*
Y-222852D02*
D03*
Y-234663D02*
D03*
Y-242537D02*
D03*
Y-230726D02*
D03*
Y-252379D02*
D03*
Y-248442D02*
D03*
X253110Y-232694D02*
D03*
Y-240568D02*
D03*
Y-234663D02*
D03*
Y-222852D02*
D03*
X269054Y-224820D02*
D03*
Y-228757D02*
D03*
Y-279938D02*
D03*
Y-258285D02*
D03*
X253110Y-238600D02*
D03*
Y-228757D02*
D03*
X269054Y-232694D02*
D03*
Y-240568D02*
D03*
Y-244505D02*
D03*
Y-260253D02*
D03*
X253110Y-224820D02*
D03*
X269054Y-250411D02*
D03*
Y-254348D02*
D03*
X253110Y-230726D02*
D03*
X269054Y-270096D02*
D03*
Y-268127D02*
D03*
X253110Y-274033D02*
D03*
Y-279938D02*
D03*
Y-244505D02*
D03*
Y-242537D02*
D03*
X269054Y-281907D02*
D03*
X253110Y-289781D02*
D03*
X269054Y-291749D02*
D03*
X253110Y-268127D02*
D03*
Y-281907D02*
D03*
Y-272064D02*
D03*
Y-270096D02*
D03*
Y-264190D02*
D03*
Y-252379D02*
D03*
Y-258285D02*
D03*
Y-287812D02*
D03*
Y-277970D02*
D03*
Y-283875D02*
D03*
Y-250411D02*
D03*
X269054Y-289781D02*
D03*
X253110Y-291749D02*
D03*
Y-262222D02*
D03*
Y-248442D02*
D03*
X269054Y-287812D02*
D03*
Y-293718D02*
D03*
Y-283875D02*
D03*
X253110Y-293718D02*
D03*
X269054Y-277970D02*
D03*
X253110Y-254348D02*
D03*
Y-260253D02*
D03*
X269054Y-274033D02*
D03*
X253110Y-220883D02*
D03*
X269054D02*
D03*
Y-285844D02*
D03*
Y-276001D02*
D03*
Y-266159D02*
D03*
Y-256316D02*
D03*
Y-246474D02*
D03*
Y-236631D02*
D03*
Y-226789D02*
D03*
X253110Y-285844D02*
D03*
Y-276001D02*
D03*
Y-266159D02*
D03*
Y-256316D02*
D03*
Y-246474D02*
D03*
Y-236631D02*
D03*
Y-226789D02*
D03*
Y-216946D02*
D03*
X269054D02*
D03*
Y-218915D02*
D03*
Y-272064D02*
D03*
X253110Y-218915D02*
D03*
X440601Y-248452D02*
D03*
Y-246484D02*
D03*
Y-272074D02*
D03*
Y-287822D02*
D03*
Y-276011D02*
D03*
Y-268137D02*
D03*
Y-279948D02*
D03*
Y-258295D02*
D03*
Y-262232D02*
D03*
X456545Y-277980D02*
D03*
Y-270106D02*
D03*
Y-276011D02*
D03*
Y-287822D02*
D03*
X440601Y-285854D02*
D03*
Y-281917D02*
D03*
Y-230736D02*
D03*
Y-252389D02*
D03*
X456545Y-272074D02*
D03*
Y-281917D02*
D03*
X440601Y-277980D02*
D03*
Y-270106D02*
D03*
Y-266169D02*
D03*
Y-250421D02*
D03*
X456545Y-285854D02*
D03*
X440601Y-260263D02*
D03*
Y-256326D02*
D03*
X456545Y-279948D02*
D03*
X440601Y-240578D02*
D03*
Y-242547D02*
D03*
X456545Y-236641D02*
D03*
Y-230736D02*
D03*
Y-266169D02*
D03*
Y-268137D02*
D03*
X440601Y-228767D02*
D03*
X456545Y-220893D02*
D03*
X440601Y-218925D02*
D03*
X456545Y-242547D02*
D03*
Y-228767D02*
D03*
Y-238610D02*
D03*
Y-240578D02*
D03*
Y-246484D02*
D03*
Y-258295D02*
D03*
Y-252389D02*
D03*
Y-222862D02*
D03*
Y-232704D02*
D03*
Y-226799D02*
D03*
Y-260263D02*
D03*
X440601Y-220893D02*
D03*
X456545Y-218925D02*
D03*
Y-248452D02*
D03*
Y-262232D02*
D03*
X440601Y-222862D02*
D03*
Y-216956D02*
D03*
Y-226799D02*
D03*
X456545Y-216956D02*
D03*
X440601Y-232704D02*
D03*
X456545Y-256326D02*
D03*
Y-250421D02*
D03*
X440601Y-236641D02*
D03*
X456545Y-289791D02*
D03*
X440601D02*
D03*
Y-224830D02*
D03*
Y-234673D02*
D03*
Y-244515D02*
D03*
Y-254358D02*
D03*
Y-264200D02*
D03*
Y-274043D02*
D03*
Y-283885D02*
D03*
X456545Y-224830D02*
D03*
Y-234673D02*
D03*
Y-244515D02*
D03*
Y-254358D02*
D03*
Y-264200D02*
D03*
Y-274043D02*
D03*
Y-283885D02*
D03*
Y-293728D02*
D03*
X440601D02*
D03*
Y-291759D02*
D03*
Y-238610D02*
D03*
X456545Y-291759D02*
D03*
D136*
X209193Y-252680D02*
D03*
X224941D02*
D03*
X209193Y-250680D02*
D03*
X224941D02*
D03*
X209193Y-248680D02*
D03*
X224941D02*
D03*
X209193Y-246680D02*
D03*
X224941D02*
D03*
X209193Y-244680D02*
D03*
X224941D02*
D03*
X209193Y-242680D02*
D03*
X224941D02*
D03*
X209193Y-240680D02*
D03*
X224941D02*
D03*
X209193Y-238680D02*
D03*
X224941D02*
D03*
X209193Y-236680D02*
D03*
X224941D02*
D03*
Y-234680D02*
D03*
X209193D02*
D03*
Y-252680D02*
D03*
X224941D02*
D03*
X209193Y-250680D02*
D03*
X224941D02*
D03*
X209193Y-248680D02*
D03*
X224941D02*
D03*
X209193Y-246680D02*
D03*
X224941D02*
D03*
X209193Y-244680D02*
D03*
X224941D02*
D03*
X209193Y-242680D02*
D03*
X224941D02*
D03*
X209193Y-240680D02*
D03*
X224941D02*
D03*
X209193Y-238680D02*
D03*
X224941D02*
D03*
X209193Y-236680D02*
D03*
X224941D02*
D03*
Y-234680D02*
D03*
X209193D02*
D03*
D137*
X599213Y-28445D02*
D03*
Y-40059D02*
D03*
D138*
X27067Y-234842D02*
D03*
Y-232874D02*
D03*
Y-230906D02*
D03*
Y-228937D02*
D03*
X14665D02*
D03*
Y-230906D02*
D03*
Y-232874D02*
D03*
Y-234842D02*
D03*
X27067Y-187205D02*
D03*
Y-185236D02*
D03*
Y-183268D02*
D03*
Y-181299D02*
D03*
X14665D02*
D03*
Y-183268D02*
D03*
Y-185236D02*
D03*
Y-187205D02*
D03*
X27067Y-291929D02*
D03*
Y-289961D02*
D03*
Y-287992D02*
D03*
Y-286024D02*
D03*
X14665D02*
D03*
Y-287992D02*
D03*
Y-289961D02*
D03*
Y-291929D02*
D03*
X21949Y-344685D02*
D03*
Y-342717D02*
D03*
Y-340748D02*
D03*
Y-338779D02*
D03*
X9547D02*
D03*
Y-340748D02*
D03*
Y-342717D02*
D03*
Y-344685D02*
D03*
D139*
X1181Y-340945D02*
D03*
Y-335433D02*
D03*
X11417Y-225984D02*
D03*
Y-220472D02*
D03*
D140*
X14567Y-280709D02*
D03*
X9055D02*
D03*
X10236Y-175591D02*
D03*
X15748D02*
D03*
D141*
X281102Y-401427D02*
D03*
X159055D02*
D03*
X155118D02*
D03*
X151181D02*
D03*
X178740D02*
D03*
X222047D02*
D03*
X265354D02*
D03*
X261417D02*
D03*
X249606D02*
D03*
X245669D02*
D03*
X233858D02*
D03*
X229921D02*
D03*
X214173D02*
D03*
X210236D02*
D03*
X186614D02*
D03*
X182677D02*
D03*
X202362D02*
D03*
X273228D02*
D03*
X166929D02*
D03*
X170866D02*
D03*
X190551D02*
D03*
X269291D02*
D03*
X257480D02*
D03*
X241732D02*
D03*
X237795D02*
D03*
X174803D02*
D03*
X162992D02*
D03*
X253543D02*
D03*
X206299D02*
D03*
X218110D02*
D03*
X225984D02*
D03*
D142*
X277165Y-399477D02*
D03*
D143*
X590551Y-35472D02*
D03*
Y-40905D02*
D03*
D144*
X620079Y-266682D02*
D03*
X620078Y-293357D02*
D03*
M02*
